G04 ================== begin FILE IDENTIFICATION RECORD ==================*
G04 Layout Name:  D:/<user>/Wistron_project/16317-1/gbr/16317-1.brd*
G04 Film Name:    L4VCC*
G04 File Format:  Gerber RS274X*
G04 File Origin:  Cadence Allegro 16.5-S056*
G04 Origin Date:  Fri Jun 09 15:53:29 2017*
G04 *
G04 Layer:  VIA CLASS/L4VCC*
G04 Layer:  PIN/L4VCC*
G04 Layer:  PACKAGE GEOMETRY/PWRVCC*
G04 Layer:  ETCH/L4VCC*
G04 Layer:  DRAWING FORMAT/LAYER_PCB_STORY*
G04 Layer:  DRAWING FORMAT/LAYER_L4VCC*
G04 *
G04 Offset:    (0.00 0.00)*
G04 Mirror:    No*
G04 Mode:      Negative*
G04 Rotation:  0*
G04 FullContactRelief:  No*
G04 UndefLineWidth:     6.00*
G04 ================== end FILE IDENTIFICATION RECORD ====================*
%FSLAX35Y35*MOIN*%
%IR0*IPPOS*OFA0.00000B0.00000*MIA0B0*SFA1.00000B1.00000*%
%ADD30C,.03*%
%ADD31C,.04*%
%ADD11C,.032*%
%ADD33C,.043*%
%ADD19C,.081*%
%ADD15C,.063*%
%ADD12C,.036*%
%ADD17C,.065*%
%ADD16C,.038*%
%ADD35C,.058*%
%ADD28C,.069*%
%AMMACRO34*
4,1,15,.00398,.00044,
.003999,.000208,
.004004,-.000025,
.003996,-.000258,
.00398,-.00044,
.00483,-.00129,
.004897,-.001007,
.004947,-.000721,
.004981,-.000432,
.004997,-.000141,
.004997,.000149,
.00498,.00044,
.004946,.000729,
.004895,.001015,
.00483,.00129,
.00398,.00044,
90.*
4,1,15,.00044,-.00398,
.000208,-.003999,
-.000025,-.004004,
-.000258,-.003996,
-.00044,-.00398,
-.00129,-.00483,
-.001007,-.004897,
-.000721,-.004947,
-.000432,-.004981,
-.000141,-.004997,
.000149,-.004997,
.00044,-.00498,
.000729,-.004946,
.001015,-.004895,
.00129,-.00483,
.00044,-.00398,
90.*
4,1,15,-.00398,-.00044,
-.003999,-.000208,
-.004004,.000025,
-.003996,.000258,
-.00398,.00044,
-.00483,.00129,
-.004897,.001007,
-.004947,.000721,
-.004981,.000432,
-.004997,.000141,
-.004997,-.000149,
-.00498,-.00044,
-.004946,-.000729,
-.004895,-.001015,
-.00483,-.00129,
-.00398,-.00044,
90.*
4,1,15,-.00044,.00398,
-.000208,.003999,
.000025,.004004,
.000258,.003996,
.00044,.00398,
.00129,.00483,
.001007,.004897,
.000721,.004947,
.000432,.004981,
.000141,.004997,
-.000149,.004997,
-.00044,.00498,
-.000729,.004946,
-.001015,.004895,
-.00129,.00483,
-.00044,.00398,
90.*
%
%ADD34MACRO34*%
%AMMACRO13*
4,1,15,.00398,.00044,
.003999,.000208,
.004004,-.000025,
.003996,-.000258,
.00398,-.00044,
.00483,-.00129,
.004897,-.001007,
.004947,-.000721,
.004981,-.000432,
.004997,-.000141,
.004997,.000149,
.00498,.00044,
.004946,.000729,
.004895,.001015,
.00483,.00129,
.00398,.00044,
0.0*
4,1,15,.00044,-.00398,
.000208,-.003999,
-.000025,-.004004,
-.000258,-.003996,
-.00044,-.00398,
-.00129,-.00483,
-.001007,-.004897,
-.000721,-.004947,
-.000432,-.004981,
-.000141,-.004997,
.000149,-.004997,
.00044,-.00498,
.000729,-.004946,
.001015,-.004895,
.00129,-.00483,
.00044,-.00398,
0.0*
4,1,15,-.00398,-.00044,
-.003999,-.000208,
-.004004,.000025,
-.003996,.000258,
-.00398,.00044,
-.00483,.00129,
-.004897,.001007,
-.004947,.000721,
-.004981,.000432,
-.004997,.000141,
-.004997,-.000149,
-.00498,-.00044,
-.004946,-.000729,
-.004895,-.001015,
-.00483,-.00129,
-.00398,-.00044,
0.0*
4,1,15,-.00044,.00398,
-.000208,.003999,
.000025,.004004,
.000258,.003996,
.00044,.00398,
.00129,.00483,
.001007,.004897,
.000721,.004947,
.000432,.004981,
.000141,.004997,
-.000149,.004997,
-.00044,.00498,
-.000729,.004946,
-.001015,.004895,
-.00129,.00483,
-.00044,.00398,
0.0*
%
%ADD13MACRO13*%
%AMMACRO22*
4,1,15,-.00398,.00044,
-.003999,.000208,
-.004004,-.000025,
-.003996,-.000258,
-.00398,-.00044,
-.00483,-.00129,
-.004897,-.001007,
-.004947,-.000721,
-.004981,-.000432,
-.004997,-.000141,
-.004997,.000149,
-.00498,.00044,
-.004946,.000729,
-.004895,.001015,
-.00483,.00129,
-.00398,.00044,
0.0*
4,1,15,-.00044,-.00398,
-.000208,-.003999,
.000025,-.004004,
.000258,-.003996,
.00044,-.00398,
.00129,-.00483,
.001007,-.004897,
.000721,-.004947,
.000432,-.004981,
.000141,-.004997,
-.000149,-.004997,
-.00044,-.00498,
-.000729,-.004946,
-.001015,-.004895,
-.00129,-.00483,
-.00044,-.00398,
0.0*
4,1,15,.00398,-.00044,
.003999,-.000208,
.004004,.000025,
.003996,.000258,
.00398,.00044,
.00483,.00129,
.004897,.001007,
.004947,.000721,
.004981,.000432,
.004997,.000141,
.004997,-.000149,
.00498,-.00044,
.004946,-.000729,
.004895,-.001015,
.00483,-.00129,
.00398,-.00044,
0.0*
4,1,15,.00044,.00398,
.000208,.003999,
-.000025,.004004,
-.000258,.003996,
-.00044,.00398,
-.00129,.00483,
-.001007,.004897,
-.000721,.004947,
-.000432,.004981,
-.000141,.004997,
.000149,.004997,
.00044,.00498,
.000729,.004946,
.001015,.004895,
.00129,.00483,
.00044,.00398,
0.0*
%
%ADD22MACRO22*%
%ADD23C,.111*%
%ADD10C,.114*%
%ADD29C,.432*%
%ADD18C,.18*%
%ADD27C,.127*%
%ADD26C,.154*%
%ADD24C,.147*%
%ADD36C,.166*%
%ADD20C,.139*%
%AMMACRO25*
4,1,15,.00398,.00044,
.003999,.000208,
.004004,-.000025,
.003996,-.000258,
.00398,-.00044,
.00483,-.00129,
.004897,-.001007,
.004947,-.000721,
.004981,-.000432,
.004997,-.000141,
.004997,.000149,
.00498,.00044,
.004946,.000729,
.004895,.001015,
.00483,.00129,
.00398,.00044,
180.*
4,1,15,.00044,-.00398,
.000208,-.003999,
-.000025,-.004004,
-.000258,-.003996,
-.00044,-.00398,
-.00129,-.00483,
-.001007,-.004897,
-.000721,-.004947,
-.000432,-.004981,
-.000141,-.004997,
.000149,-.004997,
.00044,-.00498,
.000729,-.004946,
.001015,-.004895,
.00129,-.00483,
.00044,-.00398,
180.*
4,1,15,-.00398,-.00044,
-.003999,-.000208,
-.004004,.000025,
-.003996,.000258,
-.00398,.00044,
-.00483,.00129,
-.004897,.001007,
-.004947,.000721,
-.004981,.000432,
-.004997,.000141,
-.004997,-.000149,
-.00498,-.00044,
-.004946,-.000729,
-.004895,-.001015,
-.00483,-.00129,
-.00398,-.00044,
180.*
4,1,15,-.00044,.00398,
-.000208,.003999,
.000025,.004004,
.000258,.003996,
.00044,.00398,
.00129,.00483,
.001007,.004897,
.000721,.004947,
.000432,.004981,
.000141,.004997,
-.000149,.004997,
-.00044,.00498,
-.000729,.004946,
-.001015,.004895,
-.00129,.00483,
-.00044,.00398,
180.*
%
%ADD25MACRO25*%
%AMMACRO14*
4,1,15,.00398,.00044,
.003999,.000208,
.004004,-.000025,
.003996,-.000258,
.00398,-.00044,
.00483,-.00129,
.004897,-.001007,
.004947,-.000721,
.004981,-.000432,
.004997,-.000141,
.004997,.000149,
.00498,.00044,
.004946,.000729,
.004895,.001015,
.00483,.00129,
.00398,.00044,
270.*
4,1,15,.00044,-.00398,
.000208,-.003999,
-.000025,-.004004,
-.000258,-.003996,
-.00044,-.00398,
-.00129,-.00483,
-.001007,-.004897,
-.000721,-.004947,
-.000432,-.004981,
-.000141,-.004997,
.000149,-.004997,
.00044,-.00498,
.000729,-.004946,
.001015,-.004895,
.00129,-.00483,
.00044,-.00398,
270.*
4,1,15,-.00398,-.00044,
-.003999,-.000208,
-.004004,.000025,
-.003996,.000258,
-.00398,.00044,
-.00483,.00129,
-.004897,.001007,
-.004947,.000721,
-.004981,.000432,
-.004997,.000141,
-.004997,-.000149,
-.00498,-.00044,
-.004946,-.000729,
-.004895,-.001015,
-.00483,-.00129,
-.00398,-.00044,
270.*
4,1,15,-.00044,.00398,
-.000208,.003999,
.000025,.004004,
.000258,.003996,
.00044,.00398,
.00129,.00483,
.001007,.004897,
.000721,.004947,
.000432,.004981,
.000141,.004997,
-.000149,.004997,
-.00044,.00498,
-.000729,.004946,
-.001015,.004895,
-.00129,.00483,
-.00044,.00398,
270.*
%
%ADD14MACRO14*%
%AMMACRO32*
4,1,15,-.00398,.00044,
-.003999,.000208,
-.004004,-.000025,
-.003996,-.000258,
-.00398,-.00044,
-.00483,-.00129,
-.004897,-.001007,
-.004947,-.000721,
-.004981,-.000432,
-.004997,-.000141,
-.004997,.000149,
-.00498,.00044,
-.004946,.000729,
-.004895,.001015,
-.00483,.00129,
-.00398,.00044,
180.*
4,1,15,-.00044,-.00398,
-.000208,-.003999,
.000025,-.004004,
.000258,-.003996,
.00044,-.00398,
.00129,-.00483,
.001007,-.004897,
.000721,-.004947,
.000432,-.004981,
.000141,-.004997,
-.000149,-.004997,
-.00044,-.00498,
-.000729,-.004946,
-.001015,-.004895,
-.00129,-.00483,
-.00044,-.00398,
180.*
4,1,15,.00398,-.00044,
.003999,-.000208,
.004004,.000025,
.003996,.000258,
.00398,.00044,
.00483,.00129,
.004897,.001007,
.004947,.000721,
.004981,.000432,
.004997,.000141,
.004997,-.000149,
.00498,-.00044,
.004946,-.000729,
.004895,-.001015,
.00483,-.00129,
.00398,-.00044,
180.*
4,1,15,.00044,.00398,
.000208,.003999,
-.000025,.004004,
-.000258,.003996,
-.00044,.00398,
-.00129,.00483,
-.001007,.004897,
-.000721,.004947,
-.000432,.004981,
-.000141,.004997,
.000149,.004997,
.00044,.00498,
.000729,.004946,
.001015,.004895,
.00129,.00483,
.00044,.00398,
180.*
%
%ADD32MACRO32*%
%ADD37C,.02*%
%ADD38C,.006*%
%ADD52O,.10334X.04822*%
%ADD41C,.06104*%
%ADD40C,.07704*%
%ADD47O,.515X.315*%
%ADD39C,.11004*%
%ADD44C,.14304*%
%ADD42C,.13504*%
%ADD43C,.37504*%
%ADD45C,.29531*%
%ADD48O,.55202X.78802*%
%ADD50O,.09834X.04322*%
%ADD46O,.55204X.78804*%
%ADD51O,.09836X.04324*%
%ADD49O,.09854X.04342*%
G75*
%LPD*%
G75*
G36*
G01X-6000Y-6000D02*
X1940843D01*
Y1525685D01*
X-6000D01*
Y-6000D01*
G37*
%LPC*%
G75*
G36*
G01X1085630Y1412323D02*
G03X1094567Y1421260I0J8937D01*
G01Y1505803D01*
X1103449Y1514685D01*
X1206220D01*
Y1509055D01*
G03X1215157Y1500118I8937J0D01*
G01X1240748D01*
G03X1249685Y1509055I0J8937D01*
G01Y1514685D01*
X1426890D01*
Y1500000D01*
G03X1435827Y1491063I8937J0D01*
G01X1640551D01*
G03X1649488Y1500000I0J8937D01*
G01Y1514685D01*
X1826693D01*
Y1509055D01*
G03X1835630Y1500118I8937J0D01*
G01X1861220D01*
G03X1870157Y1509055I0J8937D01*
G01Y1514685D01*
X1918031D01*
Y1464567D01*
G03X1926967Y1455630I8937J0D01*
G01X1929843D01*
Y5000D01*
X1229409D01*
Y185827D01*
G03X1220472Y194764I-8937J0D01*
G01X1064055D01*
Y244094D01*
G03X1055118Y253031I-8937J0D01*
G01X885152D01*
Y321146D01*
X880746Y325552D01*
X823354D01*
X818848Y321046D01*
Y253031D01*
G03X809961Y244095I50J-8937D01*
G01Y194764D01*
X787402D01*
G03X778465Y185827I0J-8937D01*
G01Y5000D01*
X5000D01*
Y1455630D01*
X7874D01*
G03X16811Y1464567I0J8937D01*
G01Y1514685D01*
X58976D01*
Y1509055D01*
G03X67913Y1500118I8937J0D01*
G01X93504D01*
G03X97501Y1502114I0J5000D01*
G01X99134D01*
G03X102441Y1509055I-5630J6941D01*
G01Y1514685D01*
X279646D01*
Y1500000D01*
G03X288583Y1491063I8937J0D01*
G01X493307D01*
G03X502244Y1500000I0J8937D01*
G01Y1514685D01*
X679449D01*
Y1509055D01*
G03X688386Y1500118I8937J0D01*
G01X713976D01*
G03X722913Y1509055I0J8937D01*
G01Y1514685D01*
X774528D01*
Y1500000D01*
G03X783465Y1491063I8937J0D01*
G01X988189D01*
G03X997126Y1500000I0J8937D01*
G01Y1514685D01*
X1058756D01*
X1067638Y1505803D01*
Y1421260D01*
G03X1076575Y1412323I8937J0D01*
G01X1085630D01*
G37*
G36*
G01X881150Y253031D02*
X824130D01*
X822850Y254312D01*
Y319389D01*
X825011Y321550D01*
X879089D01*
X881150Y319489D01*
Y253031D01*
G37*
%LPD*%
G75*
G36*
G01X1729037Y262991D02*
G02I-55120J0D01*
G37*
G36*
G01X558368Y715747D02*
G02I-55121J0D01*
G37*
G36*
G01X1260157Y51738D02*
X1257843D01*
G02Y55562I-1093J1912D01*
G01X1260157D01*
G02Y51738I1093J-1912D01*
G37*
G36*
G01X1384370D02*
X1382056D01*
G02Y55562I-1093J1912D01*
G01X1384370D01*
G02Y51738I1093J-1912D01*
G37*
G36*
G01X1508582D02*
X1506268D01*
G02Y55562I-1093J1912D01*
G01X1508582D01*
G02Y51738I1093J-1912D01*
G37*
G36*
G01X1632795D02*
X1630481D01*
G02Y55562I-1093J1912D01*
G01X1632795D01*
G02Y51738I1093J-1912D01*
G37*
G36*
G01X1757007D02*
X1754693D01*
G02Y55562I-1093J1912D01*
G01X1757007D01*
G02Y51738I1093J-1912D01*
G37*
G36*
G01X1881220D02*
X1878906D01*
G02Y55562I-1093J1912D01*
G01X1881220D01*
G02Y51738I1093J-1912D01*
G37*
G36*
G01X261106Y60176D02*
Y57862D01*
G02X257284I-1911J-1093D01*
G01Y60176D01*
G02X261106I1911J1093D01*
G37*
G36*
G01X1274307Y66738D02*
X1271493D01*
G02Y70562I-1093J1912D01*
G01X1274307D01*
G02Y66738I1093J-1912D01*
G37*
G36*
G01X1398520D02*
X1395706D01*
G02Y70562I-1093J1912D01*
G01X1398520D01*
G02Y66738I1093J-1912D01*
G37*
G36*
G01X1522732D02*
X1519918D01*
G02Y70562I-1093J1912D01*
G01X1522732D01*
G02Y66738I1093J-1912D01*
G37*
G36*
G01X1646945D02*
X1644131D01*
G02Y70562I-1093J1912D01*
G01X1646945D01*
G02Y66738I1093J-1912D01*
G37*
G36*
G01X1771157D02*
X1768343D01*
G02Y70562I-1093J1912D01*
G01X1771157D01*
G02Y66738I1093J-1912D01*
G37*
G36*
G01X1895370D02*
X1892556D01*
G02Y70562I-1093J1912D01*
G01X1895370D01*
G02Y66738I1093J-1912D01*
G37*
G36*
G01X378324Y75226D02*
Y72412D01*
G02X374502I-1911J-1093D01*
G01Y75226D01*
G02X378324I1911J1093D01*
G37*
G36*
G01X1575626Y103397D02*
G02X1608421Y103767I16499J-8808D01*
G02X1575626Y103397I-16295J-9279D01*
G37*
G36*
G01X906950Y300789D02*
Y320211D01*
X913250Y326511D01*
Y400189D01*
X902189Y411250D01*
X849689D01*
X842250Y418689D01*
Y593689D01*
X838689Y597250D01*
X779689D01*
X772804Y604135D01*
Y790859D01*
G03X772045Y791034I-400J-1D01*
G02X719642Y803149I-24801J12115D01*
G01Y826749D01*
G02X772045Y838864I27602J0D01*
G03X772804Y839039I359J176D01*
G01Y983146D01*
X781408Y991750D01*
X906811D01*
X917433Y981128D01*
Y943522D01*
X941505Y919450D01*
X1046906D01*
X1054450Y911906D01*
Y517500D01*
X1051000Y514050D01*
X865111D01*
X862750Y511689D01*
Y438811D01*
X865311Y436250D01*
X901500D01*
X930650Y407100D01*
Y306389D01*
X922211Y297950D01*
X909789D01*
X906950Y300789D01*
G37*
G36*
G01X1508582Y504494D02*
X1506268D01*
G02Y508318I-1093J1912D01*
G01X1508582D01*
G02Y504494I1093J-1912D01*
G37*
G36*
G01X1881220D02*
X1878906D01*
G02Y508318I-1093J1912D01*
G01X1881220D01*
G02Y504494I1093J-1912D01*
G37*
G36*
G01X136894Y512932D02*
Y510618D01*
G02X133072I-1911J-1093D01*
G01Y512932D01*
G02X136894I1911J1093D01*
G37*
G36*
G01X509532D02*
Y510618D01*
G02X505708I-1912J-1093D01*
G01Y512932D01*
G02X509532I1912J1093D01*
G37*
G36*
G01X1522732Y519494D02*
X1519918D01*
G02Y523318I-1093J1912D01*
G01X1522732D01*
G02Y519494I1093J-1912D01*
G37*
G36*
G01X1895370D02*
X1892556D01*
G02Y523318I-1093J1912D01*
G01X1895370D01*
G02Y519494I1093J-1912D01*
G37*
G36*
G01X129900Y525168D02*
G02X126076I-1912J-1093D01*
G01Y527982D01*
G02X129900I1912J1093D01*
G01Y525168D01*
G37*
G36*
G01X254112D02*
G02X250288I-1912J-1093D01*
G01Y527982D01*
G02X254112I1912J1093D01*
G01Y525168D01*
G37*
G36*
G01X1507786Y965228D02*
Y962914D01*
G02X1503964I-1911J-1093D01*
G01Y965228D01*
G02X1507786I1911J1093D01*
G37*
G36*
G01X1259402Y965268D02*
Y962954D01*
G02X1255578I-1912J-1093D01*
G01Y965268D01*
G02X1259402I1912J1093D01*
G37*
G36*
G01X1756252D02*
Y962954D01*
G02X1752428I-1912J-1093D01*
G01Y965268D01*
G02X1756252I1912J1093D01*
G37*
G36*
G01X1880464D02*
Y962954D01*
G02X1876642I-1911J-1093D01*
G01Y965268D01*
G02X1880464I1911J1093D01*
G37*
G36*
G01X1383574Y965288D02*
Y962974D01*
G02X1379752I-1911J-1093D01*
G01Y965288D01*
G02X1383574I1911J1093D01*
G37*
G36*
G01X136894Y965688D02*
Y963374D01*
G02X133071I-1911J-1093D01*
G01Y965688D01*
G02X136894I1911J1093D01*
G37*
G36*
G01X261106D02*
Y963374D01*
G02X257283I-1911J-1093D01*
G01Y965688D01*
G02X261106I1912J1093D01*
G37*
G36*
G01X385320D02*
Y963374D01*
G02X381496I-1912J-1093D01*
G01Y965688D01*
G02X385320I1912J1093D01*
G37*
G36*
G01X509532D02*
Y963374D01*
G02X505708I-1912J-1093D01*
G01Y965688D01*
G02X509532I1912J1093D01*
G37*
G36*
G01X633744D02*
Y963374D01*
G02X629922I-1911J-1093D01*
G01Y965688D01*
G02X633744I1911J1093D01*
G37*
G36*
G01X757958D02*
Y963374D01*
G02X754134I-1912J-1093D01*
G01Y965688D01*
G02X757958I1912J1093D01*
G37*
G36*
G01X1632000Y965788D02*
Y963474D01*
G02X1628176I-1912J-1093D01*
G01Y965788D01*
G02X1632000I1912J1093D01*
G37*
G36*
G01X129900Y977924D02*
G02X126076I-1912J-1093D01*
G01Y980738D01*
G02X129900I1912J1093D01*
G01Y977924D01*
G37*
G36*
G01X254112D02*
G02X250288I-1912J-1093D01*
G01Y980738D01*
G02X254112I1912J1093D01*
G01Y977924D01*
G37*
G36*
G01X378324Y980738D02*
Y977924D01*
G02X374501I-1911J-1093D01*
G01Y980738D01*
G02X378324I1911J1093D01*
G37*
G36*
G01X502536D02*
Y977924D01*
G02X498713I-1912J-1093D01*
G01Y980738D01*
G02X502536I1911J1093D01*
G37*
G36*
G01X626750D02*
Y977924D01*
G02X622926I-1912J-1093D01*
G01Y980738D01*
G02X626750I1912J1093D01*
G37*
G36*
G01X750962D02*
Y977924D01*
G02X747140I-1911J-1093D01*
G01Y980738D01*
G02X750962I1911J1093D01*
G37*
G36*
G01X1275886D02*
Y977924D01*
G02X1272064I-1911J-1093D01*
G01Y980738D01*
G02X1275886I1911J1093D01*
G37*
G36*
G01X1400100D02*
Y977924D01*
G02X1396276I-1912J-1093D01*
G01Y980738D01*
G02X1400100I1912J1093D01*
G37*
G36*
G01X1524312D02*
Y977924D01*
G02X1520488I-1912J-1093D01*
G01Y980738D01*
G02X1524312I1912J1093D01*
G37*
G36*
G01X1648524D02*
Y977924D01*
G02X1644702I-1911J-1093D01*
G01Y980738D01*
G02X1648524I1911J1093D01*
G37*
G36*
G01X1772736D02*
Y977924D01*
G02X1768914I-1911J-1093D01*
G01Y980738D01*
G02X1772736I1911J1093D01*
G37*
G36*
G01X1896950D02*
Y977924D01*
G02X1893126I-1912J-1093D01*
G01Y980738D01*
G02X1896950I1912J1093D01*
G37*
G36*
G01X623752Y1287154D02*
X620846Y1284248D01*
X598154D01*
X593748Y1288654D01*
Y1300722D01*
X408680D01*
X401248Y1308154D01*
Y1364346D01*
X404748Y1367846D01*
Y1435479D01*
X408276Y1439006D01*
X431624D01*
X443109Y1427522D01*
X485893D01*
X499163Y1414252D01*
X636252D01*
Y1410302D01*
X653600D01*
Y1411750D01*
X656161D01*
X656600Y1411311D01*
Y1410689D01*
X656161Y1410250D01*
X655100D01*
Y1294689D01*
X654661Y1294250D01*
X654039D01*
X653600Y1294689D01*
Y1295698D01*
X636252D01*
Y1291748D01*
X623752D01*
Y1287154D01*
G37*
G36*
G01X126076Y76319D02*
G02X129900I1912J0D01*
G01Y71318D01*
G02X126076Y71319I-1912J1D01*
G01Y76319D01*
G37*
G36*
G01X133072Y61269D02*
G02X136894I1911J0D01*
G01Y56768D01*
G02X133072Y56769I-1911J1D01*
G01Y61269D01*
G37*
G36*
G01X250288Y76319D02*
G02X254112I1912J0D01*
G01Y71318D01*
G02X250288Y71319I-1912J1D01*
G01Y76319D01*
G37*
G36*
G01X257284Y514025D02*
G02X261106I1911J0D01*
G01Y509524D01*
G02X257284Y509525I-1911J1D01*
G01Y514025D01*
G37*
G36*
G01X381496Y61269D02*
G02X385320I1912J0D01*
G01Y56768D01*
G02X381496Y56769I-1912J1D01*
G01Y61269D01*
G37*
G36*
G01X378324Y524075D02*
G02X374502I-1911J0D01*
G01Y529076D01*
G02X378324Y529075I1911J-1D01*
G01Y524075D01*
G37*
G36*
G01X381496Y514025D02*
G02X385320I1912J0D01*
G01Y509524D01*
G02X381496Y509525I-1912J1D01*
G01Y514025D01*
G37*
G36*
G01X498714Y76319D02*
G02X502536I1911J0D01*
G01Y71318D01*
G02X498714Y71319I-1911J1D01*
G01Y76319D01*
G37*
G36*
G01X505708Y61269D02*
G02X509532I1912J0D01*
G01Y56768D01*
G02X505708Y56769I-1912J1D01*
G01Y61269D01*
G37*
G36*
G01X502536Y524075D02*
G02X498714I-1911J0D01*
G01Y529076D01*
G02X502536Y529075I1911J-1D01*
G01Y524075D01*
G37*
G36*
G01X622926Y76319D02*
G02X626750I1912J0D01*
G01Y71318D01*
G02X622926Y71319I-1912J1D01*
G01Y76319D01*
G37*
G36*
G01X629922Y61269D02*
G02X633744I1911J0D01*
G01Y56768D01*
G02X629922Y56769I-1911J1D01*
G01Y61269D01*
G37*
G36*
G01X626750Y524075D02*
G02X622926I-1912J0D01*
G01Y529076D01*
G02X626750Y529075I1912J-1D01*
G01Y524075D01*
G37*
G36*
G01X629922Y514025D02*
G02X633744I1911J0D01*
G01Y509524D01*
G02X629922Y509525I-1911J1D01*
G01Y514025D01*
G37*
G36*
G01X754134Y61269D02*
G02X757958I1912J0D01*
G01Y56768D01*
G02X754134Y56769I-1912J1D01*
G01Y61269D01*
G37*
G36*
G01X747140Y76319D02*
G02X750962I1911J0D01*
G01Y71318D01*
G02X747140Y71319I-1911J1D01*
G01Y76319D01*
G37*
G36*
G01X754134Y514025D02*
G02X757958I1912J0D01*
G01Y509524D01*
G02X754134Y509525I-1912J1D01*
G01Y514025D01*
G37*
G36*
G01X747140Y529075D02*
G02X750962I1911J0D01*
G01Y524074D01*
G02X747140Y524075I-1911J1D01*
G01Y529075D01*
G37*
G36*
G01X1146452Y575946D02*
Y515854D01*
X1139546Y508948D01*
X1082854D01*
X1078348Y513454D01*
Y574746D01*
X1084954Y581352D01*
X1141046D01*
X1146452Y575946D01*
G37*
G36*
G01X1148652Y943346D02*
Y690154D01*
X1140946Y682448D01*
X1087354D01*
X1080348Y689454D01*
Y942841D01*
X1086959Y949452D01*
X1142546D01*
X1148652Y943346D01*
G37*
G36*
G01X1261250Y508318D02*
G02Y504494I0J-1912D01*
G01X1256749D01*
G02X1256750Y508318I1J1912D01*
G01X1261250D01*
G37*
G36*
G01X1270400Y519494D02*
G02Y523318I0J1912D01*
G01X1275401D01*
G02X1275400Y519494I-1J-1912D01*
G01X1270400D01*
G37*
G36*
G01X1399613Y523318D02*
G02Y519494I0J-1912D01*
G01X1394612D01*
G02X1394613Y523318I1J1912D01*
G01X1399613D01*
G37*
G36*
G01X1385463Y508318D02*
G02Y504494I0J-1912D01*
G01X1380962D01*
G02X1380963Y508318I1J1912D01*
G01X1385463D01*
G37*
G36*
G01X1648038Y523318D02*
G02Y519494I0J-1912D01*
G01X1643037D01*
G02X1643038Y523318I1J1912D01*
G01X1648038D01*
G37*
G36*
G01X1633888Y508318D02*
G02Y504494I0J-1912D01*
G01X1629387D01*
G02X1629388Y508318I1J1912D01*
G01X1633888D01*
G37*
G36*
G01X1767250Y519494D02*
G02Y523318I0J1912D01*
G01X1772251D01*
G02X1772250Y519494I-1J-1912D01*
G01X1767250D01*
G37*
G36*
G01X1758100Y508318D02*
G02Y504494I0J-1912D01*
G01X1753599D01*
G02X1753600Y508318I1J1912D01*
G01X1758100D01*
G37*
G36*
G01X867130Y311023D02*
G02X871454I2162J0D01*
G01Y305511D01*
G02X867130Y305512I-2162J1D01*
G01Y311023D01*
G37*
G36*
G01X878540Y300787D02*
G02X874216I-2162J0D01*
G01Y306300D01*
G02X878540Y306299I2162J-1D01*
G01Y300787D01*
G37*
G36*
G01X874216Y263779D02*
G02X878540I2162J0D01*
G01Y258267D01*
G02X874216Y258268I-2162J1D01*
G01Y263779D01*
G37*
G36*
G01X871454Y277165D02*
G02X867130I-2162J0D01*
G01Y282678D01*
G02X871454Y282677I2162J-1D01*
G01Y277165D01*
G37*
G36*
G01X828934Y291338D02*
G02X824610I-2162J0D01*
G01Y296851D01*
G02X828934Y296850I2162J-1D01*
G01Y291338D01*
G37*
G36*
G01X824610Y311023D02*
G02X828934I2162J0D01*
G01Y305511D01*
G02X824610Y305512I-2162J1D01*
G01Y311023D01*
G37*
G36*
G01X836020Y300787D02*
G02X831698I-2161J0D01*
G01Y306300D01*
G02X836020Y306299I2161J-1D01*
G01Y300787D01*
G37*
G36*
G01X838784Y311023D02*
G02X843106I2161J0D01*
G01Y305511D01*
G02X838784Y305512I-2161J1D01*
G01Y311023D01*
G37*
G36*
G01X852956D02*
G02X857280I2162J0D01*
G01Y305511D01*
G02X852956Y305512I-2162J1D01*
G01Y311023D01*
G37*
G36*
G01X850194Y300787D02*
G02X845870I-2162J0D01*
G01Y306300D01*
G02X850194Y306299I2162J-1D01*
G01Y300787D01*
G37*
G36*
G01X864366D02*
G02X860044I-2161J0D01*
G01Y306300D01*
G02X864366Y306299I2161J-1D01*
G01Y300787D01*
G37*
G36*
G01X836020Y258268D02*
G02X831698I-2161J0D01*
G01Y263780D01*
G02X836020Y263779I2161J-1D01*
G01Y258268D01*
G37*
G36*
G01X850194D02*
G02X845870I-2162J0D01*
G01Y263780D01*
G02X850194Y263779I2162J-1D01*
G01Y258268D01*
G37*
G36*
G01X864366D02*
G02X860044I-2161J0D01*
G01Y263780D01*
G02X864366Y263779I2161J-1D01*
G01Y258268D01*
G37*
G36*
G01X843106Y277165D02*
G02X838784I-2161J0D01*
G01Y282678D01*
G02X843106Y282677I2161J-1D01*
G01Y277165D01*
G37*
G36*
G01X857280D02*
G02X852956I-2162J0D01*
G01Y282678D01*
G02X857280Y282677I2162J-1D01*
G01Y277165D01*
G37*
G36*
G01X828934D02*
G02X824610I-2162J0D01*
G01Y282678D01*
G02X828934Y282677I2162J-1D01*
G01Y277165D01*
G37*
G54D41*
X1902756Y945020D03*
Y492264D03*
Y39508D03*
X1778543Y945020D03*
Y492264D03*
Y39508D03*
X1654331Y945020D03*
Y492264D03*
Y39508D03*
X1530118Y945020D03*
Y492264D03*
Y39508D03*
X1405906Y945020D03*
Y492264D03*
Y39508D03*
X1281693Y945020D03*
Y492264D03*
Y39508D03*
X732087Y945020D03*
Y492264D03*
Y39508D03*
X607874Y945020D03*
Y492264D03*
Y39508D03*
X483661Y945020D03*
Y492264D03*
Y39508D03*
X359449Y945020D03*
Y492264D03*
Y39508D03*
X235236Y945020D03*
Y492264D03*
Y39508D03*
X111024Y945020D03*
Y492264D03*
Y39508D03*
G54D40*
X1902756Y1093642D03*
Y640886D03*
Y188130D03*
X1778543Y1093642D03*
Y640886D03*
Y188130D03*
X1654331Y1093642D03*
Y640886D03*
Y188130D03*
X1530118Y1093642D03*
Y640886D03*
Y188130D03*
X1405906Y1093642D03*
Y640886D03*
Y188130D03*
X1281693Y1093642D03*
Y640886D03*
Y188130D03*
X732087Y1093642D03*
Y640886D03*
Y188130D03*
X607874Y1093642D03*
Y640886D03*
Y188130D03*
X483661Y1093642D03*
Y640886D03*
Y188130D03*
X359449Y1093642D03*
Y640886D03*
Y188130D03*
X235236Y1093642D03*
Y640886D03*
Y188130D03*
X111024Y1093642D03*
Y640886D03*
Y188130D03*
G54D47*
X256535Y1320472D03*
G54D39*
X1869500Y1461500D03*
X63374Y1454500D03*
X59400Y32600D03*
G54D44*
X1761417Y1495669D03*
X1695275D03*
X1381102D03*
X1314960D03*
X614173D03*
X548031D03*
X233858D03*
X167716D03*
G54D42*
X1840551Y122046D03*
X1343701D03*
X670079Y122047D03*
X173228D03*
G54D43*
X1840551Y55118D03*
X1343701D03*
X670078D03*
X421653Y94488D03*
X173228Y55118D03*
G54D45*
X1104527Y1162258D03*
G54D48*
X627263Y262981D03*
Y715737D03*
Y1168492D03*
X961417Y972429D03*
X1181889Y381878D03*
Y972429D03*
X1549901Y262981D03*
Y715737D03*
Y1168492D03*
X1797933Y262980D03*
Y715737D03*
Y1168492D03*
G54D46*
X131200Y262981D03*
Y715737D03*
Y1168492D03*
X379232Y262981D03*
Y715737D03*
Y1168492D03*
X747244Y381878D03*
X1301870Y262980D03*
Y715737D03*
Y1168492D03*
%LPC*%
G75*
G36*
G01X599811Y1288250D02*
X597750Y1290311D01*
Y1302811D01*
X595837Y1304724D01*
X536520D01*
G02X536396Y1305504I0J400D01*
G03X531496Y1336222I-4900J14968D01*
G01X511496D01*
G03X506596Y1305504I0J-15750D01*
G02X506472Y1304724I-124J-380D01*
G01X410337D01*
X405250Y1309811D01*
Y1362689D01*
X408750Y1366189D01*
Y1433822D01*
X409933Y1435005D01*
X429967D01*
X441452Y1423520D01*
X484236D01*
X497506Y1410250D01*
X632250D01*
Y1295750D01*
X621689D01*
X619750Y1293811D01*
Y1288811D01*
X619189Y1288250D01*
X599811D01*
G37*
G36*
G01X910411Y299450D02*
X908450Y301411D01*
Y319589D01*
X914750Y325889D01*
Y400811D01*
X902811Y412750D01*
X850311D01*
X843750Y419311D01*
Y594311D01*
X839311Y598750D01*
X780311D01*
X774304Y604757D01*
Y797708D01*
G03X774846Y803149I-27060J5443D01*
G01Y826749D01*
G03X774304Y832190I-27602J-2D01*
G01Y982524D01*
X782030Y990250D01*
X906189D01*
X915933Y980506D01*
Y942900D01*
X940883Y917950D01*
X1046284D01*
X1052950Y911284D01*
Y518122D01*
X1050378Y515550D01*
X864489D01*
X861250Y512311D01*
Y438189D01*
X864689Y434750D01*
X900878D01*
X929150Y406478D01*
Y307011D01*
X921589Y299450D01*
X910411D01*
G37*
G36*
G01X1137889Y512950D02*
X1084511D01*
X1082350Y515111D01*
Y573089D01*
X1086611Y577350D01*
X1139389D01*
X1142450Y574289D01*
Y517511D01*
X1137889Y512950D01*
G37*
G36*
G01X1139289Y686450D02*
X1089011D01*
X1084350Y691111D01*
Y941184D01*
X1088616Y945450D01*
X1140889D01*
X1144650Y941689D01*
Y691811D01*
X1139289Y686450D01*
G37*
%LPD*%
G75*
G54D52*
X1130459Y883049D03*
G54D48*
X961417Y703925D03*
G54D50*
X1130459Y569663D03*
X1116286D03*
X1126522Y520057D03*
X1130459Y527143D03*
Y541317D03*
X1126522Y548403D03*
X1102113Y569663D03*
Y527143D03*
X1098176Y548403D03*
Y520057D03*
X1126522Y932655D03*
X1130459Y925569D03*
X1126522Y861789D03*
Y904309D03*
X1098176Y932655D03*
X1102113Y925569D03*
Y883049D03*
X1098176Y861789D03*
Y904309D03*
X1130459Y812183D03*
Y854703D03*
Y840529D03*
X1126522Y833443D03*
Y790923D03*
X1130459Y769663D03*
X1102113Y812183D03*
Y854703D03*
Y840529D03*
X1098176Y833443D03*
Y790923D03*
X1102113Y769663D03*
X1126522Y762577D03*
Y720057D03*
Y748403D03*
X1130459Y741317D03*
Y698797D03*
X1126522Y691711D03*
X1098176Y762577D03*
Y720057D03*
Y748403D03*
X1102113Y741317D03*
Y698797D03*
X1098176Y691711D03*
G54D51*
X1126522Y534230D03*
X1130459Y555490D03*
X1126522Y562576D03*
X1098176Y534230D03*
X1102113Y555490D03*
X1098176Y562576D03*
X1130459Y939742D03*
X1126522Y918482D03*
X1130459Y911396D03*
X1126522Y890136D03*
X1130459Y897222D03*
X1126522Y875962D03*
X1130459Y868876D03*
X1102113Y939742D03*
X1098176Y918482D03*
X1102113Y911396D03*
X1098176Y875962D03*
Y890136D03*
X1102113Y897222D03*
Y868876D03*
X1126522Y847616D03*
X1130459Y826356D03*
X1126522Y819270D03*
Y805096D03*
X1130459Y798010D03*
Y783836D03*
X1126522Y776750D03*
X1098176Y847616D03*
X1102113Y826356D03*
X1098176Y819270D03*
Y776750D03*
X1102113Y783836D03*
Y798010D03*
X1098176Y805096D03*
X1130459Y727144D03*
Y712970D03*
Y755490D03*
X1126522Y734230D03*
Y705884D03*
X1102113Y727144D03*
Y712970D03*
Y755490D03*
X1098176Y734230D03*
Y705884D03*
G54D49*
X1102113Y541317D03*
G54D30*
X500000Y1472000D03*
X918400Y760750D03*
G54D31*
X658200Y1329200D03*
X666100D03*
Y1360800D03*
Y1368700D03*
Y1376600D03*
Y1352900D03*
X658200Y1360800D03*
Y1368700D03*
Y1376600D03*
Y1352900D03*
X666100Y1337100D03*
Y1345000D03*
X658200Y1337100D03*
Y1345000D03*
X705600Y1329200D03*
X697700Y1321300D03*
Y1329200D03*
X689800D03*
Y1321300D03*
X693800Y1313900D03*
Y1306000D03*
X685900D03*
X678000D03*
Y1313900D03*
X685900D03*
X681900Y1321300D03*
X674000D03*
Y1329200D03*
X681900D03*
X693800Y1298000D03*
X685900D03*
X678000D03*
X768867Y1311110D03*
Y1335110D03*
Y1327110D03*
Y1319110D03*
X705600Y1337100D03*
Y1360800D03*
Y1352900D03*
Y1345000D03*
Y1376600D03*
Y1368700D03*
X699600Y1408200D03*
Y1392400D03*
Y1400300D03*
X697700Y1345000D03*
Y1360800D03*
Y1368700D03*
Y1376600D03*
X697100Y1384600D03*
X697700Y1352900D03*
Y1337100D03*
X691700Y1408200D03*
Y1400300D03*
X675900D03*
X683800D03*
Y1408200D03*
X675900D03*
X689800Y1352900D03*
Y1384500D03*
Y1376600D03*
X691700Y1392400D03*
X689800Y1368700D03*
Y1360800D03*
X674000D03*
X681900D03*
Y1368700D03*
X674000D03*
X675900Y1392400D03*
X683800D03*
X674000Y1376600D03*
X681900D03*
Y1384500D03*
X674000D03*
Y1352900D03*
X681900D03*
X689800Y1345000D03*
Y1337100D03*
X681900D03*
X674000D03*
X681900Y1345000D03*
X674000D03*
X768867Y1383110D03*
Y1359110D03*
Y1367110D03*
Y1351110D03*
Y1343110D03*
Y1391110D03*
Y1399110D03*
Y1375110D03*
X786200Y1334100D03*
X794200D03*
X801000Y1333800D03*
X786200Y1326100D03*
X794200D03*
X776867Y1311110D03*
Y1335110D03*
Y1327110D03*
Y1319110D03*
X775600Y1302400D03*
X801000Y1325800D03*
X790056Y1297863D03*
X798056D03*
X782056D03*
X834000Y1324500D03*
Y1317500D03*
Y1310500D03*
Y1303500D03*
X827000D03*
X820000D03*
X827000Y1310500D03*
X820000D03*
X827000Y1317500D03*
X820000D03*
X827000Y1324500D03*
X820000D03*
X776867Y1399110D03*
X790330Y1407929D03*
X782330D03*
X798330D03*
X795000Y1377900D03*
X786600Y1378100D03*
X790950Y1372703D03*
X776867Y1383110D03*
Y1359110D03*
X782950Y1372703D03*
X776867Y1367110D03*
Y1375110D03*
X798950Y1372703D03*
X776867Y1391110D03*
X790223Y1339930D03*
X782223Y1339430D03*
X798223Y1339930D03*
X776867Y1351110D03*
Y1343110D03*
X834000Y1386000D03*
Y1379000D03*
Y1363000D03*
Y1356000D03*
Y1349000D03*
Y1342000D03*
X827000D03*
X820000D03*
X827000Y1349000D03*
X820000D03*
X827000Y1356000D03*
X820000D03*
X827000Y1363000D03*
X820000D03*
X827000Y1379000D03*
X820000D03*
X827000Y1386000D03*
X820000D03*
X827000Y1393000D03*
X820000D03*
X958200Y1303900D03*
X942400D03*
X950300D03*
X934500D03*
X926600D03*
X958200Y1311800D03*
X926600D03*
X934500D03*
X950300D03*
X942400D03*
X903500Y1319400D03*
X950300Y1319700D03*
X958200D03*
X934500D03*
X942400D03*
X926600D03*
X918700D03*
X910800D03*
X887800Y1327100D03*
X934700Y1327500D03*
X895200D03*
X903100D03*
X911000D03*
X926800D03*
X918900D03*
X887800Y1335000D03*
X886400Y1368100D03*
Y1376000D03*
X894300D03*
Y1368100D03*
X934700Y1335400D03*
X926800D03*
X918900D03*
X895200D03*
X903100D03*
X911000D03*
X890400Y1358900D03*
X887800Y1350800D03*
Y1342900D03*
X937300Y1359300D03*
X934700Y1343300D03*
Y1351200D03*
X926800Y1343300D03*
Y1351200D03*
X929400Y1359300D03*
X918900Y1343300D03*
Y1351200D03*
X921500Y1359300D03*
X918000Y1368100D03*
Y1376000D03*
X910100Y1368100D03*
Y1376000D03*
X911000Y1343300D03*
Y1351200D03*
X913600Y1359300D03*
X903100Y1343300D03*
Y1351200D03*
X905700Y1359300D03*
X902200Y1376000D03*
Y1368100D03*
X897800Y1359300D03*
X895200Y1351200D03*
Y1343300D03*
X998600Y1300900D03*
X991500Y1312100D03*
X1020800Y1300400D03*
X991455Y1320416D03*
X996400Y1315900D03*
X996200Y1307800D03*
X1014000Y1300600D03*
X991755Y1327716D03*
X996055Y1324116D03*
X1007100Y1301100D03*
X1011100Y1305300D03*
X1019829Y1306139D03*
X1002700Y1305700D03*
X991800Y1303400D03*
X1000200Y1311700D03*
Y1320500D03*
X1016429Y1333939D03*
X1021829D03*
X1011029D03*
X1005629D03*
X986755Y1323816D03*
X986700Y1307600D03*
X1000200Y1328100D03*
X997900Y1335800D03*
X992500D03*
X997900Y1341200D03*
X992500D03*
X997900Y1346600D03*
X992500D03*
X997900Y1352000D03*
X992500D03*
Y1357400D03*
X997900D03*
X989083Y1387764D03*
X989509Y1393422D03*
X994700Y1385000D03*
X999700Y1374500D03*
X989100Y1381700D03*
X994200Y1362700D03*
X1019829Y1389539D03*
X1013692Y1389688D03*
X1019829Y1361739D03*
X1014306Y1361710D03*
X1008870Y1361681D03*
X1003367Y1361655D03*
X1004217Y1389394D03*
X1008298Y1393071D03*
X994400Y1377300D03*
X999930Y1393070D03*
X999800Y1381600D03*
X999900Y1366800D03*
X994300Y1370100D03*
X989200Y1374800D03*
X988900Y1366900D03*
G54D11*
X78000Y44000D03*
X38000Y86000D03*
X86700Y80700D03*
X92250Y80500D03*
X75000Y73300D03*
X92500Y62800D03*
X95800Y71800D03*
X30500Y67000D03*
X74000Y87500D03*
X89000D03*
X84000D03*
X79000D03*
X81500Y105000D03*
X48000Y160000D03*
X95500Y186000D03*
X89000Y162700D03*
X49500Y140500D03*
X64250Y98500D03*
X73500Y120500D03*
X72900Y133000D03*
X88000Y204000D03*
X76000Y232000D03*
X50000Y200000D03*
X38000Y348000D03*
X55209Y379278D03*
X58709Y372346D03*
X38000Y418000D03*
Y452000D03*
X69942Y406555D03*
X65692Y392187D03*
X58728Y393206D03*
X84581Y397946D03*
X79581D03*
X88000Y498000D03*
Y478000D03*
X38000Y544000D03*
X81500Y557500D03*
X64250Y551000D03*
X86700Y533200D03*
X75000Y525800D03*
X92250Y533000D03*
X93800Y516800D03*
X95500Y525500D03*
X79000Y540000D03*
X84000D03*
X89000D03*
X74000D03*
X40000Y614000D03*
X76000Y642000D03*
X38000Y660000D03*
X95500Y638500D03*
X89000Y615200D03*
X73500Y573000D03*
X72800Y585500D03*
X49500Y593000D03*
X92000Y758000D03*
X34000Y792000D03*
X100000Y800000D03*
X57675Y851609D03*
X53425Y853600D03*
X46461Y853382D03*
X42942Y831932D03*
X46442Y825000D03*
X73526Y850100D03*
X68526D03*
X26000Y908000D03*
Y940000D03*
X88000Y946000D03*
X91114Y909791D03*
X85000Y885500D03*
X89000D03*
Y881500D03*
X85000D03*
X89000Y877500D03*
X85000D03*
X89000Y889500D03*
X85000D03*
X89000Y893500D03*
X85000D03*
X81166Y892754D03*
Y888754D03*
X41263Y887025D03*
X48763D03*
X55763D03*
X51263Y894525D03*
X46763Y891525D03*
X83300Y908900D03*
X100310Y899557D03*
X68900Y897700D03*
X77263Y898225D03*
X83500Y898662D03*
X73430Y898509D03*
X70603Y887495D03*
X66263Y879525D03*
X67763Y883525D03*
X81500Y1010500D03*
X38000Y996000D03*
X73500Y1026000D03*
X72600Y1038400D03*
X49500Y1046000D03*
X86700Y986200D03*
X75000Y978800D03*
X64250Y1004000D03*
X92250Y986000D03*
X95500Y968000D03*
Y972500D03*
X74000Y993000D03*
X89000D03*
X84000D03*
X79000D03*
X50000Y1100000D03*
X95500Y1091500D03*
X89000Y1068200D03*
X50000Y1150000D03*
Y1200000D03*
X100000Y1250000D03*
X50000D03*
Y1300000D03*
X100000D03*
X50000Y1350000D03*
X100000D03*
Y1400000D03*
X50000D03*
X86000Y1444000D03*
X144000Y88000D03*
X111437Y81319D03*
Y66319D03*
X106937Y84370D03*
Y93819D03*
X111437Y51319D03*
X118437Y27697D03*
X148050Y20971D03*
X126900Y39500D03*
X150700Y33100D03*
X157900Y17900D03*
X157600Y24500D03*
X157400Y35800D03*
X185551Y21529D03*
X151200Y48500D03*
Y44400D03*
X145864Y33216D03*
X175650Y28600D03*
X158000Y152000D03*
X154000Y106000D03*
X111437Y161319D03*
Y151319D03*
X173500Y140500D03*
X111437Y131319D03*
Y121319D03*
X127600Y119300D03*
X106937Y103268D03*
X131600Y119100D03*
X174000Y236000D03*
X118437Y199941D03*
X112000Y316000D03*
X162000Y310000D03*
X150000Y350000D03*
X189342Y378932D03*
X192842Y372000D03*
X102000Y440000D03*
X174000Y410000D03*
X178993Y455018D03*
Y451018D03*
X192861Y400482D03*
X182827Y447764D03*
Y455764D03*
X186827D03*
X182827Y451764D03*
X186827D03*
X182827Y439764D03*
Y443764D03*
X188941Y472055D03*
X153590Y449289D03*
X146590D03*
X149090Y456789D03*
X144590Y453789D03*
X139090Y449289D03*
X181127Y471164D03*
X166727Y459964D03*
X175090Y460489D03*
X181327Y460926D03*
X171257Y460773D03*
X168430Y449759D03*
X165590Y445789D03*
X164127Y442264D03*
X156000Y544000D03*
X130000Y560000D03*
X144000Y550000D03*
X152000Y492000D03*
X160000Y508000D03*
X188250Y550951D03*
X106937Y556024D03*
Y537126D03*
Y546575D03*
X111437Y534075D03*
Y519075D03*
Y504075D03*
X118437Y480453D03*
X176506Y539295D03*
X180500Y576000D03*
X162000Y614000D03*
X118437Y652697D03*
X111437Y614075D03*
Y604075D03*
Y584075D03*
Y574075D03*
X173500Y593000D03*
X140750Y575500D03*
X143000Y587000D03*
X174000Y686000D03*
X156000Y768000D03*
X150000Y800000D03*
X168937Y850845D03*
X163740Y846722D03*
X159740D03*
X154737Y854845D03*
Y850845D03*
X168937Y854845D03*
X176425Y853700D03*
X180400Y852300D03*
X176558Y831000D03*
X172318Y844782D03*
X169442Y824700D03*
X191026Y850100D03*
X196026D03*
X136000Y912000D03*
X140000Y938000D03*
X188000Y932000D03*
X159860Y924548D03*
X163860D03*
X168863Y916425D03*
Y920425D03*
X118437Y933209D03*
X154663Y916425D03*
Y920425D03*
X173763Y907525D03*
X189763D03*
X185763D03*
X181763D03*
X177763D03*
X193763D03*
X114563Y904041D03*
X113763Y865025D03*
X106263Y900025D03*
X106363Y893425D03*
X102207Y890524D03*
X180500Y1028500D03*
X160000Y982000D03*
X142000Y1008000D03*
X140750Y1028500D03*
X174000Y1046000D03*
X111437Y1036831D03*
Y1026831D03*
X188750Y1004000D03*
X111437Y956831D03*
Y986831D03*
Y971831D03*
X106937Y1008780D03*
Y989882D03*
Y999331D03*
X140750Y1039250D03*
X125500Y992500D03*
X136500Y1111500D03*
X164000Y1068000D03*
X118437Y1105453D03*
X111437Y1066831D03*
Y1056831D03*
X158484Y1416000D03*
X139774Y1420600D03*
X131143Y1427661D03*
X130601Y1411700D03*
X136774Y1411000D03*
X188274Y1416600D03*
X165774Y1422700D03*
X157574Y1453500D03*
X145374Y1452500D03*
X145274Y1434685D03*
X156674Y1435085D03*
X167499Y1434000D03*
X104074Y1462500D03*
X114874Y1476700D03*
X118574Y1465900D03*
X121274Y1447400D03*
X124874Y1442600D03*
X151874Y1449800D03*
X149955Y1431573D03*
X135374Y1464000D03*
Y1445500D03*
X105774Y1491000D03*
X120474Y1482800D03*
X132674Y1484200D03*
X137624Y1469000D03*
X175249Y1434075D03*
X156374Y1430500D03*
X130322Y1434014D03*
X135174Y1452400D03*
X104184Y1457200D03*
X139374Y1486100D03*
X124074Y1437200D03*
X113314Y1441700D03*
X262000Y30000D03*
X280000Y90000D03*
X264000Y94000D03*
X202500Y82500D03*
X231000Y82000D03*
X231149Y93819D03*
X235649Y81319D03*
Y66319D03*
X203300Y71700D03*
X215100Y62940D03*
X207000Y80500D03*
X235649Y51319D03*
X242649Y27697D03*
X220000Y80500D03*
X215500D03*
X203000Y87500D03*
X213000D03*
X208000D03*
X197500D03*
X284000Y160000D03*
X256000Y142000D03*
X235649Y161319D03*
Y151319D03*
X219500Y186000D03*
X213500Y162700D03*
X235649Y131319D03*
Y121319D03*
X231149Y103268D03*
X250900Y119500D03*
X197000Y133000D03*
X197500Y120500D03*
X254900Y119600D03*
X198000Y198000D03*
X212000Y236000D03*
X288000Y242000D03*
X250000Y250000D03*
X242649Y199941D03*
X214000Y328000D03*
X250000Y350000D03*
Y300000D03*
X291042Y379232D03*
X286000Y422000D03*
X257567Y409386D03*
X261567D03*
X266764Y417509D03*
Y413509D03*
X252564D03*
Y417509D03*
X199825Y400700D03*
X204075Y398609D03*
X271590Y469789D03*
X275590D03*
X279590D03*
X283590D03*
X287590D03*
X291590D03*
X218214Y397600D03*
X213214D03*
X212390Y466305D03*
X198137Y461821D03*
X204090Y462289D03*
X204190Y455689D03*
X200022Y452941D03*
X212500Y557500D03*
X216000Y498000D03*
X286000Y490000D03*
Y506000D03*
X268000Y544000D03*
X278000Y554000D03*
X266690Y479089D03*
Y483089D03*
X252490D03*
Y479089D03*
X257687Y487212D03*
X261687D03*
X231149Y556024D03*
X232433Y537126D03*
X231149Y546575D03*
X235649Y534075D03*
Y519075D03*
Y504075D03*
X242649Y480453D03*
X210700Y533200D03*
X199000Y525800D03*
X216250Y533000D03*
X218000Y516600D03*
X220000Y524000D03*
X203000Y540000D03*
X208000D03*
X213000D03*
X198000D03*
X286000Y612000D03*
X200000Y646000D03*
X242649Y652697D03*
X235649Y614075D03*
X213500Y615200D03*
X219500Y638500D03*
X235649Y604075D03*
Y584075D03*
Y574075D03*
X268187Y578998D03*
X197200Y585500D03*
X197500Y573000D03*
X264750Y586250D03*
X250000Y700000D03*
Y750000D03*
Y850000D03*
Y800000D03*
X291042Y831932D03*
X252000Y906000D03*
X212000Y916000D03*
X213500Y951500D03*
X263500Y939500D03*
X242649Y933209D03*
X197263Y901025D03*
X284500Y982000D03*
X265000Y1008500D03*
X206000Y1010500D03*
X198000Y1026000D03*
X197300Y1038500D03*
X264250Y1028500D03*
X235649Y1036831D03*
Y1026831D03*
X252100Y959100D03*
X211200Y986200D03*
X199500Y978800D03*
X216750Y986000D03*
X231149Y1008780D03*
Y989882D03*
Y999331D03*
X235649Y986831D03*
Y971831D03*
X218100Y969700D03*
X264450Y1039250D03*
X252000Y992500D03*
X220000Y978200D03*
X198500Y993000D03*
X213500D03*
X208500D03*
X203500D03*
X288000Y1068000D03*
X200000Y1100000D03*
X242649Y1105453D03*
X220000Y1091500D03*
X213500Y1068200D03*
X235649Y1066831D03*
Y1056831D03*
X200000Y1200000D03*
X250000D03*
Y1150000D03*
X200000D03*
X227500Y1303000D03*
X250000Y1350000D03*
X209374Y1416300D03*
X259500Y1494000D03*
X256000Y1466000D03*
X386000Y28000D03*
X338000Y30000D03*
Y44000D03*
X355362Y84370D03*
Y93819D03*
X359862Y81319D03*
Y66319D03*
X323500Y73300D03*
X340750Y80500D03*
X335200Y80700D03*
X359862Y51319D03*
X366862Y27697D03*
X341800Y63700D03*
X340650Y69300D03*
X327500Y87500D03*
X332500D03*
X337500D03*
X322500D03*
X359862Y161319D03*
Y151319D03*
X344000Y186000D03*
X337500Y162700D03*
X298000Y140500D03*
X359862Y131319D03*
X357506Y123493D03*
X355362Y103268D03*
X375500Y119400D03*
X312750Y98500D03*
X322000Y120500D03*
X321500Y133000D03*
X379500Y119500D03*
X324000Y196000D03*
X366862Y199941D03*
X358000Y318000D03*
X294542Y372300D03*
X320000Y422000D03*
X336000Y466000D03*
X384000Y468000D03*
X305775Y398909D03*
X301525Y400900D03*
X294561Y400682D03*
X320514Y397600D03*
X315514D03*
X295090Y463289D03*
X338000Y498000D03*
X355362Y556024D03*
Y537126D03*
Y546575D03*
X312750Y551000D03*
X359862Y534075D03*
Y519075D03*
Y504075D03*
X366862Y480453D03*
X335200Y533200D03*
X323500Y525800D03*
X340750Y533000D03*
X341800Y516800D03*
X344000Y525300D03*
X322500Y540000D03*
X337500D03*
X332500D03*
X327500D03*
X324000Y650000D03*
X359862Y614075D03*
X366862Y652697D03*
X344000Y638500D03*
X337500Y615200D03*
X359862Y604075D03*
Y584075D03*
X374261Y572963D03*
X322000Y573000D03*
X323380Y589452D03*
X298000Y593000D03*
X334000Y686000D03*
X342000Y758000D03*
X350000Y850000D03*
Y800000D03*
X301525Y853600D03*
X305775Y851609D03*
X294561Y853382D03*
X294542Y825000D03*
X320526Y850100D03*
X315526D03*
X337500Y946500D03*
X359500Y925400D03*
X330000Y1010500D03*
X304500Y1028500D03*
X359862Y1036831D03*
Y1026831D03*
X322000Y1026000D03*
X321200Y1038500D03*
X298000Y1046000D03*
X358800Y955900D03*
X355362Y1008780D03*
Y989882D03*
Y999331D03*
X359862Y986831D03*
Y971831D03*
X335200Y986200D03*
X323500Y978800D03*
X312750Y1004000D03*
X340750Y986000D03*
X341900Y969400D03*
X376000Y993000D03*
X344200Y978200D03*
X322500Y993000D03*
X337500D03*
X332500D03*
X327500D03*
X318000Y1058000D03*
X326000Y1106000D03*
X366862Y1105453D03*
X359862Y1066831D03*
Y1056831D03*
X344000Y1091500D03*
X337500Y1068200D03*
X300000Y1200000D03*
Y1150000D03*
X373492Y1317441D03*
Y1322441D03*
Y1327441D03*
Y1332441D03*
X343688Y1317736D03*
Y1322736D03*
Y1327736D03*
Y1332736D03*
X313688D03*
Y1327736D03*
Y1322736D03*
Y1317736D03*
Y1312736D03*
X369086Y1313208D03*
X374086D03*
X379086D03*
X384086D03*
X324086D03*
X329086D03*
X334086D03*
X339086D03*
X344086D03*
X349086D03*
X354086D03*
X359086D03*
X364086D03*
X294086D03*
X299086D03*
X304086D03*
X309086D03*
X319086D03*
X350000Y1400000D03*
X373492Y1337441D03*
Y1342441D03*
Y1347441D03*
Y1352441D03*
X343688Y1337736D03*
Y1342736D03*
Y1347736D03*
Y1352736D03*
X313688D03*
Y1347736D03*
Y1342736D03*
Y1337736D03*
X323688Y1357736D03*
X328688D03*
X333688D03*
X338688D03*
X343688D03*
X348688D03*
X353688D03*
X358688D03*
X363688D03*
X368688D03*
X373688D03*
X378688D03*
X383688D03*
X298688D03*
X303688D03*
X308688D03*
X313688D03*
X318688D03*
X293688D03*
X300000Y1400000D03*
X410679Y31098D03*
X414000Y58000D03*
X402000Y64000D03*
X454000Y83800D03*
X479574Y84370D03*
Y93819D03*
X462100Y62940D03*
X450300Y71700D03*
X425500Y72600D03*
X435500D03*
X430500D03*
X440500D03*
X468500Y80500D03*
X464000D03*
X446400Y91100D03*
X456900D03*
X461900D03*
X451900D03*
X467500Y116000D03*
X394000Y164000D03*
Y174000D03*
X462000Y162700D03*
X468000Y186000D03*
X422000Y140500D03*
X479574Y103268D03*
X441300Y126000D03*
X445500Y133000D03*
X440849Y111648D03*
X437500Y134500D03*
X441500D03*
X433500D03*
X388000Y196000D03*
X416000D03*
X400000Y350000D03*
X415542Y378932D03*
X419042Y372000D03*
X428000Y430000D03*
X460000Y468000D03*
X426025Y400700D03*
X419061Y400382D03*
X430275Y399351D03*
X445014Y397600D03*
X440014D03*
X402000Y560000D03*
X388000Y548000D03*
X410000Y544000D03*
X392000Y490000D03*
X460000Y496000D03*
X479574Y556024D03*
Y537126D03*
Y546575D03*
X436750Y551000D03*
X459200Y533200D03*
X446993Y527868D03*
X464750Y533000D03*
X466000Y516900D03*
X464801Y521156D03*
X446500Y540000D03*
X461500D03*
X456500D03*
X451500D03*
X410000Y616000D03*
X468000Y638500D03*
X467029Y610775D03*
X441641Y574141D03*
X445546Y586021D03*
X421820Y593641D03*
X389250Y575500D03*
X390632Y588624D03*
X422000Y684000D03*
X454000Y686000D03*
X466000Y762000D03*
X400000Y800000D03*
X425725Y853400D03*
X429975Y851409D03*
X418761Y853082D03*
X415242Y831882D03*
X418742Y824444D03*
X440026Y850100D03*
X445026D03*
X387500Y939000D03*
X462000Y947000D03*
X428500Y1028500D03*
X454000Y1010500D03*
X407000Y984000D03*
X389500Y1009000D03*
X446000Y1026000D03*
X445100Y1038500D03*
X389250Y1028500D03*
X422000Y1046000D03*
X459200Y986200D03*
X447500Y978800D03*
X436750Y1004000D03*
X464750Y986000D03*
X479574Y1008780D03*
Y989882D03*
Y999331D03*
X466100Y969200D03*
X389250Y1039250D03*
X468300Y978000D03*
X446500Y993000D03*
X461500D03*
X456500D03*
X451500D03*
X448000Y1106000D03*
X410000Y1068000D03*
X468000Y1091500D03*
X462000Y1068200D03*
X450000Y1150000D03*
Y1200000D03*
X389086Y1313208D03*
X394086D03*
X390500Y1386000D03*
X388688Y1357736D03*
X393688D03*
X532000Y90000D03*
X534000Y58000D03*
X512000Y28000D03*
X572000Y73300D03*
X484074Y81319D03*
Y66319D03*
Y51319D03*
X491074Y27697D03*
X576000Y87500D03*
X571000D03*
X556000Y156000D03*
X568000Y190000D03*
X544000Y160000D03*
X502500Y139500D03*
X512000Y104000D03*
X546500Y140500D03*
X484074Y161319D03*
Y151319D03*
X561250Y98500D03*
X570500Y120500D03*
X569900Y133000D03*
X499900Y119400D03*
X484074Y131319D03*
Y121319D03*
X503900Y119500D03*
X534000Y222500D03*
X493000Y218500D03*
X491074Y199941D03*
X539742Y379232D03*
X543242Y372300D03*
Y400682D03*
X550225Y400900D03*
X554475Y399651D03*
X569014Y397600D03*
X564014D03*
X516000Y488000D03*
X574000D03*
X524000Y560000D03*
X561250Y551000D03*
X572000Y525800D03*
X484074Y504075D03*
X491074Y480453D03*
X483513Y535912D03*
X484074Y519075D03*
X571000Y540000D03*
X576000D03*
X536000Y644000D03*
X510000Y656000D03*
X491074Y652697D03*
X484074Y614075D03*
X565279Y578552D03*
X569900Y585500D03*
X551276Y597925D03*
X483265Y606243D03*
X484074Y584075D03*
Y574075D03*
X513250Y574252D03*
X516000Y637413D03*
X517999Y583015D03*
X552000Y686000D03*
X542000Y764000D03*
X500000Y800000D03*
Y850000D03*
X564026Y850100D03*
X569026D03*
X512000Y939000D03*
X483549Y925564D03*
X513500Y1009000D03*
X532000Y983000D03*
X553000Y1028500D03*
X570500Y1026000D03*
X569900Y1038500D03*
X546500Y1046000D03*
X513250Y1028500D03*
X484074Y1036831D03*
Y1026831D03*
X572000Y978800D03*
X561250Y1004000D03*
X499800Y956831D03*
X484074Y986831D03*
Y971831D03*
X513250Y1039250D03*
X500000Y992000D03*
X571000Y993000D03*
X576000D03*
X534000Y1068000D03*
X550000Y1100000D03*
X491074Y1105453D03*
X484074Y1066831D03*
Y1056831D03*
X500000Y1150000D03*
X550000D03*
Y1200000D03*
X500000D03*
X522000Y1294000D03*
X505224Y1424156D03*
X523455Y1416564D03*
X524236Y1463672D03*
X542066Y1440238D03*
X537466D03*
X532866D03*
X528798Y1437733D03*
X524722Y1436362D03*
X528500Y1444600D03*
X507250Y1478000D03*
X535200Y1466100D03*
X523500Y1455400D03*
X503001Y1454922D03*
X513624Y1458624D03*
X504000Y1470500D03*
X503035Y1444331D03*
X528250Y1470900D03*
X496500Y1476000D03*
X508867Y1497771D03*
X585500Y45000D03*
X650000Y84000D03*
X578000Y52000D03*
X592500Y28000D03*
X603787Y84370D03*
Y93819D03*
X608287Y81319D03*
Y66319D03*
X589250Y80500D03*
X583700Y80700D03*
X608287Y51319D03*
X615287Y27697D03*
X590600Y64300D03*
X589150Y69500D03*
X581000Y87500D03*
X586000D03*
X638000Y104000D03*
X654000Y162500D03*
X664500Y97000D03*
X579000Y105000D03*
X670500Y140500D03*
X608287Y161319D03*
Y151319D03*
X592500Y186000D03*
X586000Y162700D03*
X608287Y131319D03*
Y121319D03*
X603787Y103268D03*
X624000Y119400D03*
X626000Y140000D03*
X628000Y119500D03*
X652000Y214000D03*
X582500Y266000D03*
X615287Y199941D03*
X586500Y292000D03*
X643000Y317500D03*
X614500Y318500D03*
X639000Y354500D03*
X602500Y365000D03*
X650742Y378932D03*
X654242Y372000D03*
X661225Y400738D03*
X654261Y400382D03*
X665475Y399378D03*
X638000Y488000D03*
X644000Y558000D03*
X603787Y556024D03*
Y537126D03*
Y546575D03*
X608287Y534075D03*
Y519075D03*
Y504075D03*
X615287Y480453D03*
X589250Y533000D03*
X583700Y533200D03*
X583550Y504600D03*
X592500Y525300D03*
X586000Y540000D03*
X581000D03*
X664651Y513000D03*
X671000Y648000D03*
X672500Y615500D03*
X615287Y652697D03*
X622687Y614091D03*
X592500Y638500D03*
X586043Y615962D03*
X670500Y593000D03*
X622703Y604103D03*
X623005Y584047D03*
X608287Y574075D03*
X637750Y575500D03*
X666900Y665400D03*
X637750Y586250D03*
X590000Y680000D03*
X646680Y679430D03*
X600000Y770000D03*
X650000D03*
X624000Y846000D03*
X579148Y832411D03*
X666625Y853400D03*
X670875Y851409D03*
X589805Y854600D03*
X594055Y852609D03*
X659661Y853082D03*
X582667Y853605D03*
X656142Y831632D03*
X582648Y825223D03*
X659642Y824700D03*
X585000Y948000D03*
X636000Y939000D03*
X615287Y933209D03*
X585904Y900960D03*
X589904D03*
X593904D03*
X597904D03*
X601904D03*
X673000Y885500D03*
X578000Y1010500D03*
X652500Y984500D03*
X625000Y1014500D03*
X653500Y997500D03*
X670500Y1046000D03*
X637750Y1028500D03*
X608287Y1036831D03*
Y1026831D03*
X601800Y955500D03*
X589250Y986000D03*
X603787Y1008780D03*
Y989882D03*
Y999331D03*
X608287Y986831D03*
Y971831D03*
X583700Y986200D03*
X590200Y969500D03*
X624500Y993000D03*
X592800Y978100D03*
X586000Y993000D03*
X581000D03*
X599000Y1115500D03*
X631500Y1112500D03*
X660000Y1068000D03*
X615287Y1105453D03*
X592500Y1091500D03*
X608287Y1066831D03*
Y1056831D03*
X586000Y1068200D03*
X672000Y1146000D03*
X670000Y1196000D03*
X646102Y1321750D03*
X641102D03*
X668000Y1418900D03*
X672000Y1419000D03*
X646200Y1420576D03*
X641200D03*
X637971Y1425400D03*
X657836Y1433318D03*
X658000Y1449200D03*
X653000Y1488500D03*
X665700Y1463500D03*
Y1468500D03*
X650000Y1464052D03*
Y1467948D03*
Y1457448D03*
Y1453552D03*
X636250Y1468500D03*
X628500D03*
X637972Y1441419D03*
X658000Y1444000D03*
X665700Y1458000D03*
Y1453000D03*
X624750Y1461250D03*
X729201Y87285D03*
X727636Y93834D03*
X732500Y81319D03*
Y66319D03*
X704000Y80500D03*
X699500Y82500D03*
X700300Y71700D03*
X712000Y62940D03*
X732500Y51319D03*
X739500Y27697D03*
X712214Y82500D03*
X709000Y79500D03*
X700000Y87500D03*
X705000D03*
X710000D03*
X694500D03*
X711352Y26875D03*
X715205Y27012D03*
X705171Y16254D03*
X681000Y171500D03*
X732500Y161319D03*
Y151319D03*
X716500Y186000D03*
X710300Y162700D03*
X747290Y118820D03*
X732500Y131319D03*
Y121319D03*
X728000Y103268D03*
X694500Y120500D03*
X694200Y133000D03*
X753473Y138459D03*
X714000Y240000D03*
X700000Y200000D03*
X732087Y207847D03*
X756000Y326000D03*
X718000Y332000D03*
X704500Y408500D03*
X685514Y397600D03*
X680514D03*
X716000Y568500D03*
X688000Y496000D03*
X728000Y556024D03*
Y537126D03*
Y546575D03*
X688298Y551625D03*
X732500Y504075D03*
X707700Y533200D03*
X696000Y525800D03*
X732500Y519075D03*
X713250Y533000D03*
X732500Y534075D03*
X724600Y487100D03*
X698600Y511100D03*
X714600Y498100D03*
X716400Y525200D03*
X695000Y540000D03*
X700000D03*
X705000D03*
X710000D03*
X747843Y612115D03*
X739500Y652697D03*
X710300Y635400D03*
Y615200D03*
X748200Y572200D03*
X732500Y574075D03*
X694200Y585500D03*
X732500Y584075D03*
X694500Y573000D03*
X746356Y604075D03*
X752200Y572300D03*
X710000Y760500D03*
X726500Y681500D03*
X693500Y680000D03*
X712000Y720000D03*
X709871Y686246D03*
X718100Y738500D03*
X718200Y744000D03*
X723000Y739200D03*
X723300Y743700D03*
X728175Y741300D03*
X728100Y745500D03*
X680526Y850100D03*
X685526D03*
X710000Y950500D03*
X739500Y933209D03*
X701700Y872700D03*
X714500Y870100D03*
X723600Y872400D03*
X712760Y915137D03*
X727600Y872300D03*
X733895Y901054D03*
X754000Y884524D03*
X757600Y884400D03*
X677000Y885500D03*
Y1028500D03*
X702500Y1010500D03*
X753050Y1028500D03*
X694500Y1026000D03*
X694000Y1038500D03*
X732500Y1036831D03*
Y1026831D03*
X730900Y955800D03*
X707700Y986200D03*
X696000Y978800D03*
X685250Y1004000D03*
X713250Y986000D03*
X728000Y1008780D03*
Y989882D03*
Y999331D03*
X732500Y986831D03*
Y971831D03*
X714400Y969600D03*
X755200Y992400D03*
X716800Y978300D03*
X700000Y993000D03*
X705000D03*
X710000D03*
X695000D03*
X759249Y1008800D03*
X750000Y1084000D03*
X698000Y1102000D03*
X739500Y1105453D03*
X716500Y1091500D03*
X710300Y1068200D03*
X732500Y1066831D03*
Y1056831D03*
X759700Y1138600D03*
X759762Y1135000D03*
X738000Y1152000D03*
X740000Y1202000D03*
X748000Y1170000D03*
X746000Y1218000D03*
X700000Y1150000D03*
X698500Y1418900D03*
X693000Y1418800D03*
X689000Y1419000D03*
X681000Y1419100D03*
X685000Y1418900D03*
X703500Y1426000D03*
X676500Y1419500D03*
X742880Y1422632D03*
X739532Y1425934D03*
X720455Y1438500D03*
X684000Y1482000D03*
X699500Y1476000D03*
X685000Y1453500D03*
X690000Y1448500D03*
X695000Y1453500D03*
X690000Y1458500D03*
Y1453500D03*
X724248Y1465560D03*
X730500Y1451500D03*
X685850Y1468600D03*
X724000Y1439700D03*
X717600Y1449700D03*
X746832Y1451034D03*
X735232Y1439334D03*
X739332Y1462234D03*
X750867Y1438001D03*
X722200Y1476900D03*
X680900Y1469200D03*
X680200Y1465500D03*
X675550Y1458721D03*
Y1452216D03*
X692000Y1471156D03*
X689250Y1433500D03*
X681250D03*
X745000Y1463000D03*
X730341Y1446725D03*
X756332Y1465934D03*
X745032Y1468534D03*
X732232Y1477094D03*
X718900Y1472800D03*
X679800Y1483500D03*
X708600Y1469900D03*
X724066Y1461018D03*
X724255Y1457253D03*
X735232Y1451210D03*
X771500Y251000D03*
X802000Y263500D03*
X804500Y379000D03*
X769500Y431500D03*
X807500Y473700D03*
X835165Y470414D03*
X787971Y466121D03*
X791971D03*
X787971Y461921D03*
X791971D03*
X787971Y457721D03*
X791971D03*
X848799Y457202D03*
X849539Y453596D03*
X827313Y464805D03*
X827361Y459317D03*
X832417Y459017D03*
X812282Y448094D03*
X815255Y451343D03*
X808395Y454315D03*
X834000Y499000D03*
X858740Y486430D03*
X846950Y645820D03*
Y640820D03*
X822841Y662242D03*
X794883Y639984D03*
X798475Y640227D03*
X863430Y618590D03*
X788160Y666220D03*
X814320Y651120D03*
X813980Y647430D03*
X860360Y605900D03*
X824618Y614617D03*
X827750Y611798D03*
X791530Y614700D03*
X791680Y619050D03*
X799900Y636300D03*
X807440Y629910D03*
X802900Y634000D03*
X839400Y744920D03*
X859664Y683428D03*
X837709Y681095D03*
X789442Y681063D03*
X796200Y682400D03*
X791243Y668081D03*
X778627Y735644D03*
X778683Y745049D03*
X853900Y839200D03*
X833300Y856920D03*
X841309Y796644D03*
X841800Y804499D03*
X854973Y780437D03*
X810700Y776500D03*
X818162Y819005D03*
X810659Y767500D03*
X778735Y839888D03*
X791500Y764500D03*
X795300Y764900D03*
X826000Y857400D03*
X815469Y811029D03*
X815330Y807050D03*
X858500Y845700D03*
X858100Y850000D03*
X848300Y847700D03*
X804200Y798200D03*
X811372Y795900D03*
X808372Y797900D03*
X805372Y801700D03*
X834470Y944430D03*
X842270Y942411D03*
X818434Y919985D03*
X820883Y879428D03*
X820900Y888500D03*
X825900Y862040D03*
X801300Y924300D03*
X799303Y927296D03*
X815400Y892800D03*
X844800Y895902D03*
X845732Y891713D03*
X826000Y1004000D03*
X846500Y997500D03*
X827000Y985500D03*
X796301Y959795D03*
X822470Y981470D03*
X848400Y974100D03*
X836953Y1023500D03*
X826000Y1062000D03*
X846500Y1055000D03*
X826000Y1094000D03*
Y1128000D03*
X844000Y1092000D03*
Y1128000D03*
X842700Y1071900D03*
X782712Y1211404D03*
Y1206904D03*
X772601Y1223511D03*
Y1219011D03*
Y1214511D03*
X777101Y1223511D03*
X832800Y1147500D03*
X795100Y1150400D03*
X798920Y1150500D03*
X821900Y1173700D03*
X773300Y1159700D03*
X769800Y1156500D03*
X776800Y1169700D03*
X780722Y1166357D03*
X780000Y1162800D03*
X859113Y1283983D03*
X822500Y1331000D03*
Y1298000D03*
Y1294000D03*
X860000Y1410843D03*
X842500Y1411343D03*
X852000Y1402000D03*
Y1406000D03*
X822500Y1373500D03*
Y1369500D03*
X835000Y1402500D03*
Y1398000D03*
X822500Y1335000D03*
X820000Y1448000D03*
X772361Y1451972D03*
X882823Y331182D03*
X909236Y333242D03*
X906486Y330524D03*
X910330Y363490D03*
X908340Y360430D03*
X909423Y354393D03*
X898059Y343029D03*
X902184Y347219D03*
X906616Y351586D03*
X922800Y362400D03*
X922700Y358100D03*
X945408Y378761D03*
X950843Y378827D03*
X870400Y454315D03*
X867299Y493300D03*
Y497200D03*
X922525Y519833D03*
X873000Y494100D03*
X929096Y517567D03*
X873200Y487300D03*
X944387Y520100D03*
X941557Y547005D03*
X867299Y508600D03*
Y504700D03*
X935490Y519550D03*
X878740Y655190D03*
Y647190D03*
X884801Y630225D03*
X892400Y633700D03*
X870200Y631500D03*
X867260Y608600D03*
X883030Y611940D03*
X878600Y615600D03*
X879600Y621600D03*
X878400Y626200D03*
X932986Y752682D03*
X874858Y757002D03*
X905100Y777000D03*
X915580Y857420D03*
X942500Y797867D03*
X876255Y818998D03*
X880983Y804420D03*
X874500Y774500D03*
X936543Y762518D03*
X957500Y842400D03*
X944000D03*
X924484Y812558D03*
X921047Y811463D03*
X869989Y818847D03*
X931800Y791500D03*
X870001Y822862D03*
X934800Y795300D03*
X916855Y810934D03*
X909144Y803346D03*
X903700Y803200D03*
X912762Y792801D03*
X903221Y793938D03*
X912030Y787650D03*
X907800Y788700D03*
X913059Y810367D03*
X906166Y812784D03*
X902560Y813313D03*
X876862Y842155D03*
X881702Y838859D03*
X874593Y763800D03*
X874821Y767690D03*
X931380Y821500D03*
X935485Y821400D03*
X903572Y773740D03*
X931206Y845756D03*
X920170Y857430D03*
X903500Y769900D03*
X939500Y842400D03*
X924670Y857430D03*
X866655Y855100D03*
X870200Y852203D03*
X872600Y798700D03*
X943294Y838833D03*
X903300Y763200D03*
X879205Y873548D03*
X918369Y923258D03*
X914208Y924279D03*
X883072Y886211D03*
X889458Y907846D03*
X877877Y891277D03*
X940750Y886000D03*
X928250Y885250D03*
X934500Y885156D03*
X894317Y865406D03*
X890117D03*
X894317Y861206D03*
X890117D03*
X879667Y877303D03*
X884684Y877406D03*
X895500Y1038000D03*
X944500Y1134500D03*
X952500D03*
X951500Y1117500D03*
X947000D03*
X943000D03*
X949500Y1114500D03*
X954500D03*
X956500Y1117500D03*
X948298Y1215500D03*
X943500Y1233000D03*
X951500D03*
X959500D03*
X957000Y1207500D03*
X953100Y1211400D03*
X953000Y1203600D03*
X904000Y1191700D03*
X877400D03*
X928500Y1220700D03*
X890500Y1201200D03*
X885930Y1210537D03*
X892460Y1211340D03*
X887200Y1216460D03*
X893200Y1203660D03*
X888825Y1208263D03*
X889965Y1213936D03*
X884677Y1219029D03*
X947700Y1185500D03*
X947500Y1233000D03*
X955500D03*
X926700Y1199000D03*
X952500Y1193300D03*
X884056Y1283981D03*
X871556D03*
X888000Y1424000D03*
X926000Y1420000D03*
X876500Y1410843D03*
X888776Y1402228D03*
X901435Y1402196D03*
X866500Y1392892D03*
X913935Y1402196D03*
X869937Y1400312D03*
X941559Y1408198D03*
Y1403198D03*
X866000Y1398000D03*
X945415Y1429318D03*
X945414Y1412818D03*
X866000Y1452000D03*
X900000Y1450000D03*
X944019Y1452220D03*
X1033046Y379981D03*
X1035000Y370500D03*
X1032924Y374988D03*
X1038067Y441886D03*
X1021890Y439717D03*
X965700Y519617D03*
X962118Y534117D03*
X988341Y563811D03*
X968200Y547200D03*
X985631Y559671D03*
X984197Y533383D03*
X991538Y522018D03*
X1000051Y547644D03*
X991360Y529780D03*
X964200Y855600D03*
X1009600Y851054D03*
X986471Y829716D03*
X1009950Y838000D03*
X1025636Y854819D03*
X962000Y842400D03*
X966861Y772518D03*
X977676Y828513D03*
X1005272Y837091D03*
X1000827Y837072D03*
X973070Y828512D03*
X1012125Y925875D03*
X1025251Y893000D03*
X1025065Y896965D03*
X1028500Y879500D03*
X1014807Y899075D03*
X1015007Y895000D03*
X997083Y895935D03*
X986728Y891100D03*
X974120Y858920D03*
X976242Y884600D03*
X980442Y882900D03*
X993942D03*
X996938Y901170D03*
X1034200Y945000D03*
X1040200D03*
X1046272Y944928D03*
X1039500Y874700D03*
X1024129Y946152D03*
X1044800Y893750D03*
X1030862Y951946D03*
X1022080Y960728D03*
X1032361Y1114039D03*
X1021970Y1096850D03*
X960500Y1134500D03*
X982500Y1136500D03*
X986500Y1131500D03*
X1013231Y1089300D03*
X1001687Y1111499D03*
X1008739Y1096000D03*
X961000Y1117500D03*
X1029500Y1104900D03*
X1028500Y1118601D03*
X1030178Y1134165D03*
X965500Y1128000D03*
X1012800Y1122100D03*
X1002671Y1124700D03*
X1029000Y1122400D03*
X977643Y1132490D03*
X1007431Y1122900D03*
X1020000Y1230000D03*
X971700Y1193100D03*
X963500Y1233000D03*
X967500D03*
X982500Y1217000D03*
Y1209000D03*
X960900Y1211400D03*
Y1203600D03*
X982500Y1144500D03*
Y1201000D03*
Y1197000D03*
Y1213000D03*
Y1221000D03*
Y1225000D03*
Y1205000D03*
X964550Y1190200D03*
X1054918Y1330439D03*
Y1325739D03*
X1035943Y1424649D03*
X1031443Y1426899D03*
X1040127Y1422500D03*
X1033287Y1410500D03*
X1022818Y1393489D03*
X1024193Y1422899D03*
X1010943Y1413899D03*
X1005943Y1406700D03*
X975443Y1407700D03*
X992443Y1406700D03*
X1000443D03*
X988443D03*
X996443Y1406800D03*
X983943Y1407399D03*
X979443Y1406999D03*
X964810Y1421172D03*
X1037400Y1400600D03*
X1031400Y1399200D03*
X1054918Y1386039D03*
Y1353539D03*
Y1358239D03*
Y1381339D03*
X966985Y1393900D03*
X961857D03*
X996693Y1421399D03*
X988693D03*
X1047000Y1421800D03*
X1039900Y1417000D03*
X1038303Y1441709D03*
X1021818Y1470865D03*
X1021693Y1444649D03*
X993100Y1456550D03*
X1007618Y1477365D03*
X1013418Y1470865D03*
X1027288Y1467441D03*
X1034100Y1500564D03*
X1024175Y1482189D03*
X1002118Y1471365D03*
X998325Y1471434D03*
X992443Y1441399D03*
X1002443D03*
X997443Y1436399D03*
Y1446399D03*
Y1441399D03*
X965443Y1436399D03*
X987576Y1451454D03*
Y1455054D03*
X982343Y1446620D03*
Y1440115D03*
X961877Y1445347D03*
Y1441451D03*
X999443Y1458006D03*
X1049260Y1466691D03*
X1017618Y1460865D03*
X1043606Y1437906D03*
X962136Y1431831D03*
X1033253Y1444649D03*
X1048553Y1448399D03*
X1035526Y1455899D03*
X1041176Y1455500D03*
X1020500Y1500014D03*
X1037550Y1475814D03*
X1089000Y217500D03*
X1150000Y250000D03*
X1100000D03*
X1098000Y378000D03*
X1136000D03*
X1100000Y350000D03*
Y300000D03*
X1150000D03*
X1144000Y418000D03*
X1136100Y460288D03*
X1147440Y473040D03*
X1143720Y468520D03*
X1143420Y472900D03*
X1139590Y468380D03*
X1139330Y472820D03*
X1135410Y468380D03*
X1135310Y472820D03*
X1130800Y472900D03*
X1131800Y446800D03*
X1136000Y446849D03*
X1092000Y448400D03*
X1088000Y448500D03*
X1103100Y457300D03*
X1095100Y455800D03*
X1113593Y476094D03*
X1093000Y502000D03*
X1149964Y481623D03*
X1102677Y487116D03*
X1119242Y477261D03*
X1083000Y620000D03*
X1095000D03*
X1112298Y618498D03*
X1134600Y618747D03*
X1118505Y658863D03*
X1114905Y658882D03*
X1129500Y619200D03*
X1138900Y584900D03*
X1125025Y621993D03*
X1056116Y697100D03*
X1057826Y680233D03*
X1059927Y688329D03*
X1064216Y683751D03*
X1067554Y694447D03*
X1071179Y682315D03*
X1112682Y681223D03*
X1107674Y677776D03*
X1141230Y673825D03*
X1103770Y675413D03*
X1075706Y941261D03*
X1141370Y905550D03*
X1058800Y893750D03*
X1130000Y994000D03*
X1106000D03*
X1138000Y970000D03*
X1093588Y972000D03*
X1110600Y964200D03*
X1108500Y960600D03*
X1104600Y967800D03*
X1101950Y962900D03*
X1101600Y953700D03*
X1087962Y959252D03*
X1084000Y1092000D03*
X1130000Y1154000D03*
X1078000Y1166000D03*
X1080000Y1230000D03*
X1068569Y1191530D03*
X1072931Y1191482D03*
X1072900Y1204500D03*
X1084571Y1200129D03*
X1072600Y1211400D03*
X1084400Y1204200D03*
X1121346Y1315676D03*
Y1319676D03*
X1100625Y1292025D03*
X1107000Y1323500D03*
X1083100Y1305600D03*
X1082080Y1299375D03*
X1126820Y1288500D03*
X1075030Y1323078D03*
X1078850Y1287900D03*
X1082080Y1309495D03*
X1123000Y1297600D03*
X1096280Y1288150D03*
X1092475Y1287971D03*
X1133480Y1296700D03*
Y1291700D03*
X1121346Y1307385D03*
Y1311385D03*
X1117000Y1332500D03*
Y1328500D03*
X1072120Y1299375D03*
Y1304495D03*
Y1309495D03*
Y1292460D03*
X1114000Y1430000D03*
X1105100Y1351000D03*
Y1355000D03*
X1124612Y1388773D03*
X1130112Y1363273D03*
X1138112D03*
X1132112Y1380773D03*
X1114112Y1363273D03*
X1118112D03*
X1126112D03*
X1099112Y1387273D03*
Y1379273D03*
X1110512Y1403273D03*
X1067712Y1384766D03*
X1099112Y1391273D03*
X1099100Y1375200D03*
X1099112Y1383273D03*
X1099100Y1371200D03*
X1117362Y1406073D03*
X1134112Y1363273D03*
X1122112D03*
X1091000Y1393500D03*
X1086646Y1396419D03*
X1126112Y1401773D03*
X1130873Y1490848D03*
Y1495848D03*
X1238000Y164000D03*
X1236500Y216000D03*
X1200000Y250000D03*
X1218000Y344000D03*
X1225600Y368700D03*
X1200000Y300000D03*
X1190000Y466000D03*
X1184000Y440000D03*
X1206000Y430500D03*
X1160900Y468500D03*
X1156110Y473330D03*
X1152600Y468470D03*
X1245567Y420602D03*
X1243500Y393600D03*
X1201000Y447000D03*
X1200500Y452000D03*
X1169000Y511500D03*
X1150900Y485100D03*
X1177100Y495300D03*
X1167000Y586500D03*
X1232490Y664290D03*
X1236690D03*
X1171700Y603700D03*
X1172500Y599700D03*
X1169125Y581776D03*
X1166550Y579200D03*
X1177350Y597792D03*
X1188000Y753500D03*
X1212587Y740895D03*
Y736695D03*
Y732495D03*
X1232490Y668490D03*
X1212587Y728295D03*
X1236690Y668490D03*
X1212587Y724095D03*
X1232490Y672690D03*
X1212587Y719895D03*
X1236690Y672690D03*
X1206414Y704261D03*
X1209931Y701608D03*
X1207468Y697962D03*
X1210283Y695565D03*
X1212587Y749295D03*
Y745095D03*
X1232490Y685290D03*
X1179129Y672187D03*
X1232490Y681090D03*
X1180000Y832000D03*
Y848000D03*
X1217089Y846182D03*
X1224088Y844900D03*
X1213611Y831932D03*
X1228344Y852351D03*
X1190995Y776395D03*
X1186690Y791440D03*
X1217111Y825000D03*
X1173990Y797760D03*
X1177300Y804960D03*
X1180520Y790880D03*
X1179690Y798020D03*
X1200337Y912300D03*
X1200407Y918060D03*
X1157556Y932754D03*
X1184778Y912848D03*
X1180090Y896524D03*
X1181550Y906100D03*
X1184750Y889200D03*
Y896300D03*
X1240000Y1070000D03*
X1176000D03*
X1200000Y1100000D03*
X1155600Y1074500D03*
X1178000Y1214000D03*
X1200000Y1200000D03*
Y1150000D03*
X1223730Y1285803D03*
X1230600D03*
X1235600D03*
X1216894Y1318783D03*
Y1314783D03*
X1202394Y1285803D03*
X1197394D03*
X1190524D03*
X1183894Y1319783D03*
Y1315783D03*
X1193894Y1292533D03*
X1227100D03*
X1205624D03*
X1238830D03*
X1185324Y1286563D03*
X1220450Y1292533D03*
X1216894Y1304283D03*
Y1308283D03*
X1183894Y1304783D03*
Y1308783D03*
X1196000Y1366000D03*
X1212000D03*
X1242000Y1412000D03*
X1236600Y1346763D03*
X1232100D03*
X1217100D03*
X1183894D03*
X1203394D03*
X1198894D03*
X1178712Y1372573D03*
X1200962Y1413023D03*
X1209819Y1417377D03*
X1188894Y1346763D03*
X1222000Y1346700D03*
X1180614Y1340033D03*
X1213820D03*
X1243768Y1376953D03*
X1208394Y1346763D03*
X1193894D03*
X1227100D03*
X1203312Y1402793D03*
X1241600Y1346763D03*
X1169412Y1396873D03*
X1226000Y1436000D03*
X1238000Y1444000D03*
X1190000Y1494000D03*
X1156000D03*
X1200000Y1450000D03*
X1326000Y92000D03*
X1298655Y59926D03*
X1282106Y81319D03*
Y66319D03*
X1299800Y56000D03*
X1278038Y93821D03*
X1278698Y84340D03*
X1307200Y45000D03*
X1289106Y27697D03*
X1282106Y51319D03*
X1303500Y35000D03*
X1308000D03*
X1309500Y76500D03*
X1314500D03*
X1299500D03*
X1304500D03*
X1261100Y16600D03*
X1264700Y16400D03*
X1262000Y174000D03*
X1313000Y185500D03*
X1314000Y150500D03*
X1282106Y161319D03*
Y151319D03*
X1302500Y152000D03*
X1305000Y185500D03*
X1298500D03*
X1282106Y131319D03*
Y121319D03*
X1266600Y119500D03*
X1262468Y103268D03*
X1256800Y132400D03*
X1262600Y119700D03*
X1272500Y213000D03*
X1307500Y205000D03*
X1338000Y225000D03*
X1289106Y199941D03*
X1252000Y358000D03*
X1294500Y331500D03*
X1278500Y313000D03*
X1259445Y379019D03*
X1337824Y379176D03*
X1262945Y377600D03*
X1294624Y358802D03*
X1317500Y435500D03*
X1316000Y419000D03*
X1269926Y400687D03*
X1262964Y400469D03*
X1281693Y473218D03*
X1274396Y407915D03*
X1247949Y423302D03*
X1250648Y425686D03*
X1245959Y435527D03*
X1265295Y421223D03*
X1257000Y434600D03*
X1248500Y393600D03*
X1298500Y562500D03*
X1317500Y533500D03*
X1277606Y546575D03*
Y556024D03*
Y537126D03*
X1307500Y501500D03*
X1299900Y534200D03*
X1311200Y511500D03*
X1282106Y519075D03*
Y534075D03*
Y504075D03*
X1303800Y522500D03*
X1327000Y487000D03*
X1325500Y504750D03*
X1312000Y501500D03*
X1272182Y571361D03*
X1334500Y549500D03*
Y554500D03*
Y539500D03*
Y544500D03*
X1318000Y660000D03*
X1332000Y646000D03*
X1312973Y643128D03*
X1282106Y614075D03*
X1273979Y652690D03*
X1305000Y638500D03*
X1298000Y638300D03*
X1314000Y603500D03*
X1282106Y574075D03*
Y604075D03*
Y584075D03*
X1302500Y605000D03*
X1272211Y575575D03*
X1254000Y748000D03*
X1312000Y812000D03*
X1278000Y810000D03*
X1250000Y820000D03*
X1337824Y832935D03*
X1247588Y842190D03*
X1310000Y860000D03*
X1270000Y868000D03*
X1274000Y933209D03*
X1325500Y907000D03*
X1298000Y1014000D03*
X1318000Y986000D03*
X1266000Y1046000D03*
X1252000Y1010000D03*
X1266400Y1024700D03*
X1282106Y1036831D03*
Y1026831D03*
X1300600Y986800D03*
X1307500Y954000D03*
X1311200Y964000D03*
X1282106Y956831D03*
X1303800Y975000D03*
X1277606Y1008780D03*
Y999331D03*
Y989882D03*
X1282106Y986831D03*
Y971831D03*
X1325500Y957250D03*
X1262400Y1024700D03*
X1312000Y954000D03*
X1260000Y993500D03*
X1334500Y1002000D03*
Y1007000D03*
Y992000D03*
Y997000D03*
X1266000Y1128000D03*
X1264000Y1082000D03*
X1250000Y1100000D03*
X1289106Y1105453D03*
X1314000Y1056000D03*
X1313000Y1091000D03*
X1298500D03*
X1302500Y1057500D03*
X1305000Y1091000D03*
X1282106Y1066831D03*
Y1056831D03*
X1250000Y1200000D03*
Y1150000D03*
X1288000Y1296000D03*
X1274000Y1314000D03*
X1300000Y1388000D03*
X1274000Y1374000D03*
X1318540Y1424331D03*
X1273874Y1423000D03*
X1314375Y1424375D03*
X1327900Y1416500D03*
X1266914Y1394873D03*
X1258187Y1389753D03*
X1281624Y1409209D03*
X1253165Y1384633D03*
X1246949Y1379513D03*
X1263642Y1392313D03*
X1261224Y1387193D03*
X1277624Y1409209D03*
X1250347Y1382073D03*
X1306625Y1434000D03*
X1303874Y1453750D03*
X1292374Y1452500D03*
X1301534Y1431345D03*
X1289124Y1430700D03*
X1253374Y1459300D03*
X1260874Y1481400D03*
X1264774Y1470700D03*
X1266574Y1452300D03*
X1289574Y1483700D03*
X1252674Y1496800D03*
X1266474Y1487500D03*
X1278574Y1488700D03*
X1282374Y1445500D03*
Y1464000D03*
X1296374Y1430700D03*
X1297089Y1450307D03*
X1322000Y1430700D03*
X1284624Y1476400D03*
X1253374Y1470000D03*
X1260574Y1445600D03*
X1256474Y1446000D03*
X1432000Y30000D03*
X1358000Y91000D03*
X1406319Y66319D03*
Y81319D03*
X1401819Y93819D03*
Y84370D03*
X1435200Y58500D03*
X1427800Y69500D03*
X1406319Y51319D03*
X1413319Y27697D03*
X1431500Y48500D03*
X1436000D03*
X1392500Y173000D03*
X1389000Y148500D03*
X1422000Y98000D03*
X1346000Y179000D03*
X1351500Y144500D03*
X1406319Y151319D03*
Y161319D03*
X1426500Y152000D03*
X1422500Y185500D03*
X1429000D03*
X1406319Y121319D03*
Y131319D03*
X1401819Y103268D03*
X1391200Y119500D03*
X1376700Y136000D03*
X1394200Y113700D03*
X1428000Y238000D03*
X1388500Y230000D03*
X1394000Y249000D03*
X1397937Y199951D03*
X1373000Y234500D03*
X1388000Y378000D03*
X1400000Y350000D03*
X1341324Y372244D03*
X1378000Y430000D03*
X1376000Y414000D03*
X1436500Y430000D03*
X1341343Y400626D03*
X1348305Y400844D03*
X1352557Y399595D03*
X1367514Y397100D03*
X1362514D03*
X1384000Y554000D03*
X1352000Y516000D03*
X1432000Y482000D03*
X1364000Y492000D03*
X1401819Y546575D03*
Y556024D03*
Y537126D03*
X1406319Y534075D03*
Y519075D03*
Y504075D03*
X1413319Y480453D03*
X1424400Y534200D03*
X1431500Y501500D03*
X1435200Y511500D03*
X1427800Y522500D03*
X1436000Y501500D03*
X1345215Y533601D03*
X1382000Y592000D03*
X1384000Y646000D03*
X1358000Y600000D03*
X1413319Y652697D03*
X1406319Y614075D03*
X1422500Y638500D03*
X1429000D03*
X1406319Y604075D03*
Y584075D03*
Y574075D03*
X1394110Y575530D03*
X1426500Y605000D03*
X1383952Y573102D03*
X1430000Y752000D03*
X1346000Y704000D03*
X1382000Y688000D03*
X1384000Y782000D03*
X1400000Y850000D03*
X1348305Y853600D03*
X1341343Y853382D03*
X1352557Y852351D03*
X1341324Y825000D03*
X1367500Y851922D03*
X1362500D03*
X1413319Y933209D03*
X1342000Y976000D03*
X1356000Y998000D03*
X1424100Y987000D03*
X1391000Y1024800D03*
X1406319Y1036831D03*
Y1026831D03*
Y956831D03*
X1431500Y954000D03*
X1435200Y964000D03*
X1427800Y975000D03*
X1401819Y1008780D03*
Y999331D03*
Y989882D03*
X1406319Y986831D03*
Y971831D03*
X1386900Y1024600D03*
X1383200Y992700D03*
X1436000Y954000D03*
X1360000Y1054000D03*
X1350000Y1100000D03*
X1413319Y1105453D03*
X1426500Y1057500D03*
X1422500Y1091000D03*
X1429000D03*
X1406319Y1066831D03*
Y1056831D03*
X1350000Y1150000D03*
X1400000D03*
Y1200000D03*
X1350000D03*
X1366000Y1388000D03*
X1347400Y1416200D03*
X1406000Y1444000D03*
X1474000Y78000D03*
X1508000Y36000D03*
X1468000Y42000D03*
X1482000Y66000D03*
X1530531Y66319D03*
Y81319D03*
X1526031Y93819D03*
Y84370D03*
X1439500Y81000D03*
X1530531Y51319D03*
X1458500Y86500D03*
Y91500D03*
X1508500Y102500D03*
X1441100Y130800D03*
X1494000Y98000D03*
X1484000Y158000D03*
X1530531Y151319D03*
X1526823Y161308D03*
X1437000Y185500D03*
X1438000Y150500D03*
X1530531Y121319D03*
Y131319D03*
X1526031Y103268D03*
X1515400Y119400D03*
X1501300Y136100D03*
X1511400Y119500D03*
X1458500Y96500D03*
Y101500D03*
X1523100Y193700D03*
X1502000Y196000D03*
X1457500Y289000D03*
X1508500Y292500D03*
X1450000Y350000D03*
X1462036Y379176D03*
X1465536Y372244D03*
X1484000Y432000D03*
X1476769Y399595D03*
X1465555Y400626D03*
X1472517Y400844D03*
X1492014Y397100D03*
X1487014D03*
X1442500Y532000D03*
X1480000Y546000D03*
X1510000Y488000D03*
X1476000Y518000D03*
X1526031Y546575D03*
Y556024D03*
Y537126D03*
X1530531Y534075D03*
Y519075D03*
Y504075D03*
X1449500Y504750D03*
X1458500Y544500D03*
Y539500D03*
Y554500D03*
Y549500D03*
X1451800Y583800D03*
X1498000Y586000D03*
X1490000Y598000D03*
X1500000Y640000D03*
X1460000Y646000D03*
X1530531Y614075D03*
X1437000Y638500D03*
X1530531Y604075D03*
Y584075D03*
Y574075D03*
X1515200Y572200D03*
X1438000Y603500D03*
X1511200Y572300D03*
X1508000Y748000D03*
X1472517Y853600D03*
X1465555Y853382D03*
X1462036Y831932D03*
X1476769Y852351D03*
X1465536Y825000D03*
X1493500Y853100D03*
X1487000Y851600D03*
X1443992Y904962D03*
X1442500Y984500D03*
X1478000Y976000D03*
X1480000Y1020000D03*
X1515400Y1025000D03*
X1530531Y1036831D03*
Y1026831D03*
Y956831D03*
X1526031Y1008780D03*
Y999331D03*
Y989882D03*
X1530531Y986831D03*
Y971831D03*
X1450100Y959500D03*
X1511400Y1024600D03*
X1506000Y993000D03*
X1458500Y1002000D03*
Y1007000D03*
Y992000D03*
Y997000D03*
X1500000Y1100000D03*
X1530531Y1066831D03*
Y1056831D03*
X1437000Y1091000D03*
X1438000Y1056000D03*
X1450000Y1150000D03*
X1500000D03*
Y1200000D03*
X1450000D03*
X1500000Y1300000D03*
X1450000D03*
Y1350000D03*
X1500000D03*
Y1450000D03*
X1450000D03*
X1594000Y56000D03*
X1574000Y26000D03*
X1608000Y62000D03*
Y50000D03*
X1549300Y56000D03*
X1548500Y62900D03*
X1553000Y35000D03*
X1556700Y45000D03*
X1537531Y27697D03*
X1557500Y35000D03*
X1549000Y76500D03*
X1554000D03*
X1564000D03*
X1559000D03*
X1593500Y160500D03*
X1546000Y112000D03*
X1547000Y156222D03*
Y185500D03*
X1562500Y150500D03*
X1561500Y185500D03*
X1553500Y189500D03*
X1625300Y136000D03*
X1598000Y206000D03*
X1568000Y204000D03*
X1592000Y236000D03*
X1616100Y203786D03*
X1550000Y350000D03*
X1586249Y379176D03*
X1589749Y372244D03*
X1553500Y431500D03*
X1604000Y432500D03*
X1600982Y399595D03*
X1596730Y400844D03*
X1589768Y400626D03*
X1611014Y397100D03*
X1616014D03*
X1566500Y533000D03*
X1604000Y536000D03*
X1594000Y506000D03*
X1558000Y482000D03*
X1559700Y511500D03*
X1556000Y501500D03*
X1548600Y534900D03*
X1552300Y522500D03*
X1537531Y480453D03*
X1574000Y504750D03*
X1560500Y501500D03*
X1583000Y544500D03*
Y539500D03*
Y554500D03*
Y549500D03*
X1570100Y583800D03*
X1568000Y660000D03*
X1584000Y648000D03*
X1553500Y638500D03*
X1561500Y639860D03*
X1537500Y656000D03*
X1551000Y605000D03*
X1562500Y603500D03*
X1602000Y684000D03*
X1566000Y772000D03*
X1550000Y850000D03*
X1596730Y853600D03*
X1589768Y853382D03*
X1586249Y831932D03*
X1597000Y857500D03*
X1591400Y825000D03*
X1616000Y850100D03*
X1611000D03*
X1599000Y941000D03*
X1579000Y940000D03*
X1564000Y876000D03*
X1537531Y933209D03*
X1572900Y902900D03*
X1604000Y1022000D03*
X1544000Y1004500D03*
X1566500Y985500D03*
X1600500Y975000D03*
X1612000Y980000D03*
X1548900Y987600D03*
X1556000Y954000D03*
X1559700Y964000D03*
X1552300Y975000D03*
X1574000Y957250D03*
X1560500Y954000D03*
X1583000Y997000D03*
Y992000D03*
Y1007000D03*
Y1002000D03*
X1561500Y1091000D03*
X1553500D03*
X1600000Y1100000D03*
X1537531Y1105453D03*
X1551000Y1057500D03*
X1547000Y1091000D03*
X1562500Y1056000D03*
X1600000Y1200000D03*
Y1150000D03*
X1550000Y1300000D03*
X1600000D03*
X1550000Y1350000D03*
X1600000D03*
Y1450000D03*
X1550000D03*
X1718000Y66000D03*
X1680000Y26000D03*
X1632000D03*
X1676300Y69500D03*
X1683700Y58500D03*
X1686730Y80991D03*
X1654744Y66319D03*
Y81319D03*
X1650244Y93819D03*
Y84370D03*
X1680000Y48500D03*
X1654744Y51319D03*
X1661744Y27697D03*
X1684500Y48500D03*
X1692200Y86200D03*
Y91200D03*
X1636000Y176000D03*
X1677500Y185500D03*
X1686500Y150500D03*
X1675000Y152000D03*
X1654744Y151319D03*
Y161319D03*
X1685500Y185500D03*
X1654744Y121319D03*
X1653206Y134559D03*
X1650244Y103268D03*
X1639300Y119500D03*
X1635300Y119600D03*
X1692300Y96100D03*
X1707000Y103500D03*
X1648000Y212000D03*
X1682000Y206000D03*
X1661744Y199941D03*
X1671003Y190635D03*
X1712525Y191268D03*
X1650000Y380000D03*
X1638500Y311500D03*
X1715000Y305500D03*
X1648000Y468000D03*
X1714000Y391000D03*
X1721762Y458436D03*
Y454436D03*
X1696359Y452707D03*
X1689359D03*
X1691859Y460207D03*
X1687359Y457207D03*
X1681859Y452707D03*
X1709496Y463382D03*
X1717859Y463907D03*
X1714026Y464191D03*
X1711199Y453177D03*
X1708359Y449207D03*
X1706859Y445207D03*
X1682000Y484000D03*
X1720000Y506000D03*
X1650244Y546575D03*
Y556024D03*
Y537126D03*
X1654744Y534075D03*
Y519075D03*
Y504075D03*
X1661744Y480453D03*
X1680000Y501500D03*
X1673200Y535100D03*
X1683700Y511500D03*
X1676300Y522500D03*
X1698000Y504750D03*
X1684500Y501500D03*
X1707083Y543435D03*
Y538435D03*
X1706800Y556300D03*
X1706935Y548158D03*
X1706000Y646000D03*
X1632000Y648000D03*
X1634000Y618000D03*
X1661744Y652697D03*
X1654744Y614075D03*
X1671000Y638500D03*
X1685500D03*
X1677500D03*
X1654744Y604075D03*
Y584075D03*
X1652808Y574040D03*
X1686500Y603500D03*
X1675000Y605000D03*
X1638200Y572200D03*
X1634200D03*
X1700000Y700000D03*
X1650000D03*
Y750000D03*
X1700000D03*
X1650000Y850000D03*
X1720942Y853600D03*
X1713980Y853382D03*
X1710461Y831932D03*
X1713961Y825000D03*
X1690200Y937700D03*
X1718000Y938000D03*
X1716000Y878000D03*
X1661800Y933400D03*
X1709500Y900700D03*
X1668000Y1004000D03*
X1690500Y986000D03*
X1672800Y987300D03*
X1639100Y1024900D03*
X1654744Y1036831D03*
Y1026831D03*
Y956831D03*
X1676300Y975000D03*
X1683700Y964000D03*
X1680000Y954000D03*
X1650244Y1008780D03*
Y999331D03*
Y989882D03*
X1654744Y986831D03*
Y971831D03*
X1698000Y957250D03*
X1635100Y1024700D03*
X1631500Y994000D03*
X1684500Y954000D03*
X1707000Y997000D03*
Y992000D03*
Y1007000D03*
Y1002000D03*
X1638000Y1082000D03*
X1696000Y1106000D03*
X1661744Y1105453D03*
X1677500Y1091000D03*
X1686500Y1056000D03*
X1671000Y1091000D03*
X1675000Y1057500D03*
X1685500Y1091000D03*
X1654744Y1066831D03*
Y1056831D03*
X1650000Y1150000D03*
X1700000D03*
Y1200000D03*
X1650000D03*
Y1300000D03*
X1676511Y1292495D03*
X1674000Y1410000D03*
X1650000Y1350000D03*
X1669376Y1429200D03*
X1651906Y1428973D03*
X1719726Y1402700D03*
X1716026Y1416500D03*
X1663906Y1428973D03*
X1659906D03*
X1694751Y1434000D03*
X1683926Y1453750D03*
X1672626Y1452500D03*
X1686226Y1432500D03*
X1656250Y1461250D03*
X1662626Y1464000D03*
Y1445500D03*
X1674926Y1447400D03*
X1676626Y1432000D03*
X1702501Y1434000D03*
X1661626Y1480000D03*
X1756000Y25500D03*
X1730000Y58000D03*
X1811700Y59550D03*
X1808600Y78200D03*
X1803500Y82200D03*
X1778956Y66319D03*
Y81319D03*
X1774456Y93819D03*
Y84370D03*
X1785956Y27697D03*
X1778956Y51319D03*
X1795600Y44900D03*
X1817500Y32700D03*
X1814850Y21500D03*
X1811600Y32800D03*
X1794300Y63400D03*
X1796300Y85600D03*
X1806300D03*
X1811300D03*
X1801300D03*
X1803620Y57000D03*
X1807500Y57400D03*
X1730500Y177500D03*
X1730000Y136000D03*
X1746000Y106000D03*
X1809500Y185500D03*
X1801500D03*
X1811305Y147994D03*
X1799000Y152000D03*
X1795000Y185500D03*
X1778956Y151319D03*
Y161319D03*
Y121319D03*
Y131319D03*
X1774456Y103268D03*
X1763600Y119400D03*
X1749700Y135600D03*
X1759600Y119500D03*
X1804000Y205000D03*
X1724000Y232000D03*
X1754000Y234000D03*
X1750000Y200000D03*
X1785956Y199941D03*
X1768000Y310000D03*
X1781500Y366000D03*
X1801642Y379532D03*
X1805142Y372600D03*
X1724000Y422000D03*
X1745737Y400643D03*
X1800436Y412804D03*
X1804436D03*
X1809633Y420927D03*
Y416927D03*
X1795433D03*
Y420927D03*
X1759904Y400647D03*
X1812123Y401200D03*
X1805142Y400982D03*
X1814359Y473207D03*
X1725596Y447182D03*
X1729596Y443182D03*
X1725596D03*
X1729596Y455182D03*
X1725596D03*
X1729596Y459182D03*
X1725596D03*
Y451182D03*
X1729596Y447182D03*
Y451182D03*
X1731710Y475473D03*
X1749952Y405830D03*
X1764168Y405501D03*
X1816375Y399951D03*
X1723896Y474582D03*
X1753631Y405830D03*
X1735014Y397100D03*
X1740014D03*
X1755159Y469723D03*
X1740906Y465239D03*
X1746859Y465707D03*
X1724096Y464344D03*
X1746959Y459107D03*
X1742758Y456059D03*
X1813700Y548300D03*
X1796000Y566500D03*
X1728000Y554000D03*
X1757200Y558900D03*
X1730000Y568000D03*
X1809559Y482507D03*
Y486507D03*
X1795359D03*
Y482507D03*
X1800556Y490630D03*
X1804556D03*
X1774456Y556024D03*
X1767342Y533721D03*
X1774456Y546575D03*
X1785956Y480453D03*
X1804000Y501500D03*
X1807700Y511500D03*
X1800300Y522500D03*
X1798100Y537973D03*
X1785728Y538736D03*
X1778956Y519075D03*
Y504075D03*
X1808500Y501500D03*
X1818000Y656000D03*
X1762000Y628000D03*
X1756000Y646000D03*
X1785956Y652697D03*
X1795000Y638500D03*
X1801500D03*
X1809500D03*
X1778956Y614075D03*
X1810500Y603500D03*
X1799000Y605000D03*
X1778956Y604075D03*
Y584075D03*
Y574075D03*
X1759750Y576000D03*
Y587000D03*
X1758000Y748000D03*
X1756000Y684000D03*
X1808000Y848000D03*
X1760000Y846000D03*
X1800000Y800000D03*
X1725194Y852351D03*
X1740000Y850100D03*
X1735000D03*
X1778500Y917500D03*
X1738000Y904000D03*
X1796166Y892754D03*
Y888754D03*
X1785956Y933209D03*
X1804000Y885500D03*
Y881500D03*
X1800000Y885500D03*
Y893500D03*
X1804000D03*
X1800000Y889500D03*
X1804000D03*
X1800000Y877500D03*
X1804000D03*
X1800000Y881500D03*
X1806114Y909791D03*
X1770763Y887025D03*
X1763763D03*
X1766263Y894525D03*
X1761763Y891525D03*
X1756263Y887025D03*
X1798300Y908900D03*
X1815310Y899557D03*
X1783900Y897700D03*
X1792263Y898225D03*
X1798500Y898662D03*
X1788430Y898509D03*
X1817739Y889758D03*
X1785603Y887495D03*
X1782763Y883525D03*
X1781263Y879525D03*
X1794500Y1007000D03*
X1814500Y985500D03*
X1724000Y974000D03*
X1728000Y1002000D03*
X1796900Y987200D03*
X1763300Y1024800D03*
X1778956Y1036831D03*
Y1026831D03*
X1800300Y975000D03*
X1804000Y954000D03*
X1807700Y964000D03*
X1778956Y956831D03*
X1774456Y1008780D03*
Y999331D03*
Y989882D03*
X1778956Y986831D03*
Y971831D03*
X1759300Y1024900D03*
X1808500Y954000D03*
X1756000Y993500D03*
X1730000Y1050000D03*
X1762000Y1080000D03*
X1785956Y1105453D03*
X1809500Y1091000D03*
X1801500D03*
X1810500Y1056000D03*
X1795000Y1091000D03*
X1799000Y1057500D03*
X1778956Y1066831D03*
Y1056831D03*
X1750000Y1150000D03*
Y1200000D03*
X1800000Y1300000D03*
Y1250000D03*
X1760000Y1394000D03*
X1800000Y1350000D03*
X1735126Y1416300D03*
X1790226Y1458600D03*
X1803426Y1452600D03*
X1804326Y1480500D03*
X1794226Y1473300D03*
X1810426Y1476200D03*
X1790226Y1469300D03*
X1800326Y1445800D03*
X1794426Y1446400D03*
X1820200Y70140D03*
X1898669Y93819D03*
Y84370D03*
X1903169Y66319D03*
Y81319D03*
X1885200Y81000D03*
X1871400Y82000D03*
X1903169Y51319D03*
X1910169Y27697D03*
X1887900Y41300D03*
X1878000Y29300D03*
X1884600Y49000D03*
X1821850Y35400D03*
X1824200Y23400D03*
Y19000D03*
X1868600Y68922D03*
X1872900Y49000D03*
X1885508Y77413D03*
X1891300Y49400D03*
X1880500Y48900D03*
X1842400Y29500D03*
X1875500Y87000D03*
X1880500D03*
X1865500D03*
X1870500D03*
X1851500Y171500D03*
X1867600Y104300D03*
X1903169Y151319D03*
Y161319D03*
X1881000Y162200D03*
X1883000Y181500D03*
X1841000Y140000D03*
X1903169Y121319D03*
Y131319D03*
X1898669Y103268D03*
X1860817Y120141D03*
X1864800Y132500D03*
X1834018Y169783D03*
X1840500Y237500D03*
X1850000Y200000D03*
X1900000Y250000D03*
X1910169Y199941D03*
X1829500Y311000D03*
X1900000Y300000D03*
Y350000D03*
X1830000Y424000D03*
X1838000Y415500D03*
X1850000Y400000D03*
X1900000D03*
Y450000D03*
X1818359Y473207D03*
X1822359D03*
X1826359D03*
X1830359D03*
X1834359D03*
X1827114Y397900D03*
X1832114D03*
X1836476Y467034D03*
X1884000Y488000D03*
X1854000Y482000D03*
X1875000Y558000D03*
X1898669Y546575D03*
Y556024D03*
Y537126D03*
X1883200Y534600D03*
X1855750Y551000D03*
X1903169Y534075D03*
Y519075D03*
Y504075D03*
X1910169Y480453D03*
X1866700Y512800D03*
X1866500Y507250D03*
X1859300Y524500D03*
X1822000Y504750D03*
X1848500Y504000D03*
X1883300Y530000D03*
X1853000Y504000D03*
X1870500Y540500D03*
X1865500D03*
X1880500D03*
X1875500D03*
X1831000Y544500D03*
Y539500D03*
Y554500D03*
Y549500D03*
X1851400Y623800D03*
X1850000Y650000D03*
X1910169Y652697D03*
X1903169Y614075D03*
X1880500Y615200D03*
X1887000Y638500D03*
X1903169Y604075D03*
Y584075D03*
Y574075D03*
X1865000Y573000D03*
X1864700Y585500D03*
X1841000Y593000D03*
X1846000Y686000D03*
X1900000Y750000D03*
Y700000D03*
Y800000D03*
X1874540Y847322D03*
X1878540D03*
X1883737Y855445D03*
Y851445D03*
X1869537D03*
Y855445D03*
X1849407Y852351D03*
X1845155Y853600D03*
X1838193Y853382D03*
X1834674Y831932D03*
X1838174Y825000D03*
X1859500Y850100D03*
X1864500D03*
X1883663Y917025D03*
Y921025D03*
X1874660Y925148D03*
X1878660D03*
X1869463Y921025D03*
Y917025D03*
X1910169Y933209D03*
X1888763Y907525D03*
X1892763D03*
X1896763D03*
X1900763D03*
X1904763D03*
X1908763D03*
X1820700Y940600D03*
X1848500Y940200D03*
X1829563Y904041D03*
X1828763Y865025D03*
X1821263Y900025D03*
X1821363Y893425D03*
X1872500Y1010500D03*
X1826000Y1036500D03*
X1864500Y1038500D03*
X1865000Y1026000D03*
X1903169Y1036831D03*
Y1026831D03*
X1841000Y1046000D03*
X1903169Y956831D03*
X1859600Y960250D03*
X1883100Y984750D03*
X1870800Y973100D03*
X1898669Y1008780D03*
Y999331D03*
Y989882D03*
X1903169Y986831D03*
Y971831D03*
X1855750Y1004000D03*
X1859300Y977500D03*
X1822000Y957250D03*
X1848500Y957000D03*
X1875800Y981000D03*
X1853000Y957000D03*
X1865500Y993000D03*
X1881814Y993136D03*
X1876814D03*
X1871814D03*
X1831000Y1002000D03*
Y1007000D03*
Y992000D03*
Y997000D03*
X1827600Y970700D03*
X1850000Y1078000D03*
X1910169Y1105453D03*
X1887000Y1091500D03*
X1880500Y1068200D03*
X1903169Y1066831D03*
Y1056831D03*
X1850000Y1200000D03*
X1900000D03*
Y1150000D03*
X1850000D03*
X1900000Y1300000D03*
X1850000D03*
X1900000Y1250000D03*
X1850000D03*
X1900000Y1400000D03*
X1850000D03*
Y1350000D03*
X1900000D03*
X1904000Y1504000D03*
X1878000Y1484000D03*
X1822000Y1444000D03*
X1900000Y1450000D03*
X1824826Y1470900D03*
X1822326Y1481600D03*
X1919000Y51000D03*
X1922400Y470400D03*
X1923600Y913525D03*
X1914500Y902000D03*
X1918800Y1112100D03*
G54D33*
X862205Y277953D03*
X848032D03*
X833859D03*
X862205Y272441D03*
X848032D03*
X833859D03*
X862205Y263779D03*
X848032D03*
X833859D03*
X862205Y258268D03*
X848032D03*
X833859D03*
X855118Y282677D03*
X840945D03*
X826772D03*
X855118Y277165D03*
X840945D03*
X826772D03*
X855118Y268504D03*
X840945D03*
X826772D03*
X855118Y262992D03*
X840945D03*
X826772D03*
X862205Y306299D03*
X848032D03*
X833859D03*
X862205Y300787D03*
X848032D03*
X833859D03*
X862205Y292126D03*
X848032D03*
X833859D03*
X862205Y286614D03*
X848032D03*
X833859D03*
X855118Y311023D03*
X840945D03*
X826772D03*
X855118Y305512D03*
X840945D03*
X826772D03*
X855118Y296850D03*
X840945D03*
X826772D03*
X855118Y291338D03*
X840945D03*
X826772D03*
X904725Y272835D03*
Y277165D03*
Y282677D03*
X911811Y272441D03*
Y277953D03*
Y282283D03*
X904725Y262992D03*
Y268504D03*
X911811Y253937D03*
Y258268D03*
Y263779D03*
Y268110D03*
X897638Y282283D03*
Y272441D03*
Y277953D03*
Y253937D03*
Y268110D03*
Y258268D03*
Y263779D03*
X890552Y272835D03*
Y277165D03*
Y282677D03*
Y262992D03*
Y268504D03*
X876378Y277953D03*
Y272441D03*
Y263779D03*
Y258268D03*
X869292Y282677D03*
Y277165D03*
Y268504D03*
Y262992D03*
X904725Y305512D03*
Y311023D03*
Y315354D03*
X911811Y310630D03*
X904725Y301181D03*
X911811Y300787D03*
X904725Y287008D03*
Y291338D03*
Y296850D03*
X911811Y286614D03*
Y292126D03*
Y296457D03*
X897638Y310630D03*
Y306299D03*
Y296457D03*
Y286614D03*
Y292126D03*
Y300787D03*
X890552Y315354D03*
Y305512D03*
Y311023D03*
Y287008D03*
Y301181D03*
Y291338D03*
Y296850D03*
X876378Y306299D03*
Y300787D03*
Y292126D03*
Y286614D03*
X869292Y311023D03*
Y305512D03*
Y296850D03*
Y291338D03*
X1095420Y520057D03*
X1100932D03*
X1109593D03*
X1115105D03*
X1123766D03*
X1129278D03*
X1099357Y527143D03*
X1104869D03*
X1113530D03*
X1119042D03*
X1127703D03*
X1133215D03*
X1095420Y534230D03*
X1100932D03*
X1109593D03*
X1115105D03*
X1123766D03*
X1129278D03*
X1099357Y541317D03*
X1104869D03*
X1113530D03*
X1119042D03*
X1127703D03*
X1133215D03*
X1095420Y548403D03*
X1100932D03*
X1109593D03*
X1115105D03*
X1123766D03*
X1129278D03*
X1099357Y555490D03*
X1104869D03*
X1113530D03*
X1119042D03*
X1127703D03*
X1133215D03*
X1095420Y562576D03*
X1100932D03*
X1109593D03*
X1115105D03*
X1123766D03*
X1129278D03*
X1099357Y569663D03*
X1104869D03*
X1113530D03*
X1119042D03*
X1127703D03*
X1133215D03*
X1095420Y691711D03*
Y705884D03*
Y720057D03*
Y734230D03*
Y748403D03*
Y762577D03*
X1100932Y691711D03*
Y705884D03*
Y720057D03*
Y734230D03*
Y748403D03*
Y762577D03*
X1109593Y691711D03*
Y705884D03*
Y720057D03*
Y734230D03*
Y748403D03*
Y762577D03*
X1115105Y691711D03*
Y705884D03*
Y720057D03*
Y734230D03*
Y748403D03*
Y762577D03*
X1123766Y691711D03*
Y705884D03*
Y720057D03*
Y734230D03*
Y748403D03*
Y762577D03*
X1129278Y691711D03*
Y705884D03*
Y720057D03*
Y734230D03*
Y748403D03*
Y762577D03*
X1099357Y698797D03*
Y712970D03*
Y727144D03*
Y741317D03*
Y755490D03*
X1104869Y698797D03*
Y712970D03*
Y727144D03*
Y741317D03*
Y755490D03*
X1113530Y698797D03*
Y712970D03*
Y727144D03*
Y741317D03*
Y755490D03*
X1119042Y698797D03*
Y712970D03*
Y727144D03*
Y741317D03*
Y755490D03*
X1127703Y698797D03*
Y712970D03*
Y727144D03*
Y741317D03*
Y755490D03*
X1133215Y698797D03*
Y712970D03*
Y727144D03*
Y741317D03*
Y755490D03*
X1095420Y776750D03*
Y790923D03*
Y805096D03*
Y819270D03*
Y833443D03*
Y847616D03*
X1100932Y776750D03*
Y790923D03*
Y805096D03*
Y819270D03*
Y833443D03*
Y847616D03*
X1109593Y776750D03*
Y790923D03*
Y805096D03*
Y819270D03*
Y833443D03*
Y847616D03*
X1115105Y776750D03*
Y790923D03*
Y805096D03*
Y819270D03*
Y833443D03*
Y847616D03*
X1123766Y776750D03*
Y790923D03*
Y805096D03*
Y819270D03*
Y833443D03*
Y847616D03*
X1129278Y776750D03*
Y790923D03*
Y805096D03*
Y819270D03*
Y833443D03*
Y847616D03*
X1099357Y769663D03*
Y783836D03*
Y798010D03*
Y812183D03*
Y826356D03*
Y840529D03*
Y854703D03*
X1104869Y769663D03*
Y783836D03*
Y798010D03*
Y812183D03*
Y826356D03*
Y840529D03*
Y854703D03*
X1113530Y769663D03*
Y783836D03*
Y798010D03*
Y812183D03*
Y826356D03*
Y840529D03*
Y854703D03*
X1119042Y769663D03*
Y783836D03*
Y798010D03*
Y812183D03*
Y826356D03*
Y840529D03*
Y854703D03*
X1127703Y769663D03*
Y783836D03*
Y798010D03*
Y812183D03*
Y826356D03*
Y840529D03*
Y854703D03*
X1133215Y769663D03*
Y783836D03*
Y798010D03*
Y812183D03*
Y826356D03*
Y840529D03*
Y854703D03*
X1095420Y861789D03*
Y875962D03*
Y890136D03*
Y904309D03*
Y918482D03*
Y932655D03*
X1100932Y861789D03*
Y875962D03*
Y890136D03*
Y904309D03*
Y918482D03*
Y932655D03*
X1109593Y861789D03*
Y875962D03*
Y890136D03*
Y904309D03*
Y918482D03*
Y932655D03*
X1115105Y861789D03*
Y875962D03*
Y890136D03*
Y904309D03*
Y918482D03*
Y932655D03*
X1123766Y861789D03*
Y875962D03*
Y890136D03*
Y904309D03*
Y918482D03*
Y932655D03*
X1129278Y861789D03*
Y875962D03*
Y890136D03*
Y904309D03*
Y918482D03*
Y932655D03*
X1099357Y868876D03*
Y883049D03*
Y897222D03*
Y911396D03*
Y925569D03*
Y939742D03*
X1104869Y868876D03*
Y883049D03*
Y897222D03*
Y911396D03*
Y925569D03*
Y939742D03*
X1113530Y868876D03*
Y883049D03*
Y897222D03*
Y911396D03*
Y925569D03*
Y939742D03*
X1119042Y868876D03*
Y883049D03*
Y897222D03*
Y911396D03*
Y925569D03*
Y939742D03*
X1127703Y868876D03*
Y883049D03*
Y897222D03*
Y911396D03*
Y925569D03*
Y939742D03*
X1133215Y868876D03*
Y883049D03*
Y897222D03*
Y911396D03*
Y925569D03*
Y939742D03*
G54D12*
X100412Y6000D03*
X95412D03*
X90412D03*
X85412D03*
X80412D03*
X75412D03*
X70412D03*
X65412D03*
X60412D03*
X55412D03*
X50412D03*
X45412D03*
X40412D03*
X35412D03*
X30412D03*
X25412D03*
X20412D03*
X15412D03*
X10412D03*
X6000Y6588D03*
Y11588D03*
Y16588D03*
Y21588D03*
Y26588D03*
Y31588D03*
Y36588D03*
Y41588D03*
Y46588D03*
Y51588D03*
Y56588D03*
Y61588D03*
Y66588D03*
Y71588D03*
Y76588D03*
Y81588D03*
Y86588D03*
Y91588D03*
Y96588D03*
Y101588D03*
Y106588D03*
Y111588D03*
Y116588D03*
Y121588D03*
Y126588D03*
Y131588D03*
Y136588D03*
Y141588D03*
Y146588D03*
Y151588D03*
Y156588D03*
Y161588D03*
Y166588D03*
Y171588D03*
Y176588D03*
Y181588D03*
Y186588D03*
Y191588D03*
Y196588D03*
Y201588D03*
Y206588D03*
Y211588D03*
Y216588D03*
Y221588D03*
Y226588D03*
Y231588D03*
Y236588D03*
Y241588D03*
Y246588D03*
Y251588D03*
Y256588D03*
Y261588D03*
Y266588D03*
Y271588D03*
Y276588D03*
Y281588D03*
Y286588D03*
Y291588D03*
Y296588D03*
Y301588D03*
Y306588D03*
Y311588D03*
Y316588D03*
Y321588D03*
Y326588D03*
Y331588D03*
Y336588D03*
Y341588D03*
Y346588D03*
Y351588D03*
Y356588D03*
Y361588D03*
Y366588D03*
Y371588D03*
Y376588D03*
Y441588D03*
Y436588D03*
Y431588D03*
Y426588D03*
Y421588D03*
Y416588D03*
Y411588D03*
Y406588D03*
Y386588D03*
Y391588D03*
Y396588D03*
Y401588D03*
Y446588D03*
Y451588D03*
Y456588D03*
Y461588D03*
Y381588D03*
Y466588D03*
Y471588D03*
Y476588D03*
Y481588D03*
Y486588D03*
Y491588D03*
Y496588D03*
Y501588D03*
Y506588D03*
Y511588D03*
Y516588D03*
Y521588D03*
Y526588D03*
Y531588D03*
Y536588D03*
Y541588D03*
Y546588D03*
Y551588D03*
Y556588D03*
Y561588D03*
Y566588D03*
Y571588D03*
Y576588D03*
Y581588D03*
Y586588D03*
Y591588D03*
Y596588D03*
Y601588D03*
Y606588D03*
Y611588D03*
Y616588D03*
Y621588D03*
Y626588D03*
Y631588D03*
Y636588D03*
Y641588D03*
Y646588D03*
Y651588D03*
Y656588D03*
Y661588D03*
Y666588D03*
Y671588D03*
Y676588D03*
Y681588D03*
Y686588D03*
Y691588D03*
Y696588D03*
Y701588D03*
Y706588D03*
Y711588D03*
Y716588D03*
Y721588D03*
Y726588D03*
Y731588D03*
Y736588D03*
Y741588D03*
Y746588D03*
Y751588D03*
Y756588D03*
Y761588D03*
Y766588D03*
Y771588D03*
Y776588D03*
Y781588D03*
Y786588D03*
Y791588D03*
Y796588D03*
Y801588D03*
Y806588D03*
Y811588D03*
Y816588D03*
Y821588D03*
Y826588D03*
Y831588D03*
Y836588D03*
Y841588D03*
Y846588D03*
Y851588D03*
Y856588D03*
Y861588D03*
Y866588D03*
Y871588D03*
Y876588D03*
Y881588D03*
Y886588D03*
Y891588D03*
Y896588D03*
Y901588D03*
Y906588D03*
Y911588D03*
Y916588D03*
Y921588D03*
Y926588D03*
Y931588D03*
Y936588D03*
Y941588D03*
Y946588D03*
Y951588D03*
Y956588D03*
Y961588D03*
Y966588D03*
Y971588D03*
Y976588D03*
Y981588D03*
Y986588D03*
Y991588D03*
Y996588D03*
Y1001588D03*
Y1006588D03*
Y1011588D03*
Y1016588D03*
Y1021588D03*
Y1026588D03*
Y1031588D03*
Y1036588D03*
Y1041588D03*
Y1046588D03*
Y1051588D03*
Y1056588D03*
Y1061588D03*
Y1066588D03*
Y1071588D03*
Y1076588D03*
Y1081588D03*
Y1086588D03*
Y1091588D03*
Y1096588D03*
Y1101588D03*
Y1106588D03*
Y1111588D03*
Y1116588D03*
Y1121588D03*
Y1126588D03*
Y1131588D03*
Y1136588D03*
Y1141588D03*
Y1146588D03*
Y1151588D03*
Y1156588D03*
Y1161588D03*
Y1166588D03*
Y1171588D03*
Y1176588D03*
Y1181588D03*
Y1186588D03*
Y1191588D03*
Y1196588D03*
Y1201588D03*
Y1206588D03*
Y1211588D03*
Y1216588D03*
Y1221588D03*
Y1226588D03*
Y1231588D03*
Y1236588D03*
Y1321588D03*
Y1326588D03*
Y1331588D03*
Y1286588D03*
Y1291588D03*
Y1296588D03*
Y1301588D03*
Y1306588D03*
Y1311588D03*
Y1316588D03*
Y1241588D03*
Y1246588D03*
Y1251588D03*
Y1256588D03*
Y1261588D03*
Y1266588D03*
Y1271588D03*
Y1276588D03*
Y1281588D03*
Y1421588D03*
Y1416588D03*
Y1411588D03*
Y1406588D03*
Y1401588D03*
Y1396588D03*
Y1391588D03*
Y1386588D03*
Y1381588D03*
Y1376588D03*
Y1371588D03*
Y1366588D03*
Y1361588D03*
Y1356588D03*
Y1351588D03*
Y1346588D03*
Y1341588D03*
Y1426588D03*
Y1336588D03*
Y1451588D03*
Y1446588D03*
Y1441588D03*
Y1436588D03*
Y1431588D03*
X99000Y1501000D03*
X61500Y1502000D03*
X87539Y1499118D03*
X82539D03*
X77539D03*
X72539D03*
X67539D03*
X92539D03*
X11000Y1455500D03*
X15500Y1458500D03*
X17811Y1462693D03*
Y1467693D03*
Y1472693D03*
Y1477693D03*
Y1482693D03*
Y1487693D03*
Y1492693D03*
Y1497693D03*
Y1502693D03*
Y1507693D03*
X17500Y1512000D03*
X21819Y1513685D03*
X26819D03*
X31819D03*
X36819D03*
X41819D03*
X46819D03*
X51819D03*
X56819D03*
X58500Y1508000D03*
X195412Y6000D03*
X190412D03*
X185412D03*
X180412D03*
X175412D03*
X170412D03*
X165412D03*
X160412D03*
X155412D03*
X150412D03*
X145412D03*
X140412D03*
X135412D03*
X130412D03*
X125412D03*
X120412D03*
X115412D03*
X110412D03*
X105412D03*
X169215Y876085D03*
Y880885D03*
X154215D03*
Y876085D03*
X169215Y895685D03*
Y890885D03*
X154215Y895685D03*
Y890885D03*
X164200Y885700D03*
X158900D03*
X192963Y888625D03*
Y883625D03*
X188163Y888625D03*
X183363D03*
X178563D03*
Y883625D03*
X173763D03*
Y888625D03*
X183363Y883625D03*
X188163D03*
X113363Y884925D03*
X180000Y1424000D03*
Y1430000D03*
X186000Y1424000D03*
Y1430000D03*
X152000Y1377000D03*
Y1383000D03*
X158000Y1377000D03*
Y1383000D03*
X170000D03*
Y1377000D03*
X164000Y1383000D03*
Y1377000D03*
X102000Y1505500D03*
X177433Y1513685D03*
X182433D03*
X187433D03*
X192433D03*
X147433D03*
X152433D03*
X157433D03*
X162433D03*
X167433D03*
X172433D03*
X103000Y1511000D03*
X107433Y1513685D03*
X112433D03*
X117433D03*
X122433D03*
X127433D03*
X132433D03*
X137433D03*
X142433D03*
X290412Y6000D03*
X285412D03*
X280412D03*
X275412D03*
X270412D03*
X265412D03*
X260412D03*
X255412D03*
X250412D03*
X245412D03*
X240412D03*
X235412D03*
X230412D03*
X225412D03*
X220412D03*
X215412D03*
X210412D03*
X205412D03*
X200412D03*
X251200Y457900D03*
Y438300D03*
Y443100D03*
Y453100D03*
X291500Y451100D03*
Y446100D03*
X286700D03*
Y451100D03*
X281900D03*
Y446100D03*
X272300D03*
Y451100D03*
X277100Y446100D03*
Y451100D03*
X267752Y458160D03*
Y438560D03*
Y443360D03*
Y453360D03*
X257127Y448364D03*
X261927D03*
X211590Y427289D03*
X211190Y447189D03*
X197763Y888625D03*
Y883625D03*
X233074Y1429500D03*
X239274Y1429600D03*
X237235Y1419039D03*
X236974Y1425000D03*
X283000Y1492000D03*
X279000Y1498500D03*
X197433Y1513685D03*
X202433D03*
X207433D03*
X212433D03*
X217433D03*
X222433D03*
X227433D03*
X232433D03*
X237433D03*
X242433D03*
X247433D03*
X252433D03*
X257433D03*
X262433D03*
X267433D03*
X272433D03*
X277433D03*
X278646Y1509398D03*
Y1504398D03*
X288685Y1490063D03*
X385412Y6000D03*
X380412D03*
X375412D03*
X370412D03*
X365412D03*
X360412D03*
X355412D03*
X350412D03*
X345412D03*
X340412D03*
X335412D03*
X330412D03*
X325412D03*
X320412D03*
X315412D03*
X310412D03*
X305412D03*
X300412D03*
X295412D03*
X296300Y446100D03*
Y451100D03*
X380780Y1428599D03*
Y1422599D03*
Y1416599D03*
Y1410599D03*
X374780Y1428599D03*
Y1422599D03*
Y1416599D03*
Y1410599D03*
X293685Y1490063D03*
X298685D03*
X303685D03*
X308685D03*
X313685D03*
X318685D03*
X323685D03*
X328685D03*
X333685D03*
X338685D03*
X343685D03*
X348685D03*
X353685D03*
X358685D03*
X363685D03*
X368685D03*
X373685D03*
X378685D03*
X383685D03*
X380780Y1434599D03*
X374780D03*
X480412Y6000D03*
X475412D03*
X470412D03*
X465412D03*
X460412D03*
X455412D03*
X450412D03*
X445412D03*
X440412D03*
X435412D03*
X430412D03*
X425412D03*
X420412D03*
X415412D03*
X410412D03*
X405412D03*
X400412D03*
X395412D03*
X390412D03*
X388685Y1490063D03*
X393685D03*
X398685D03*
X403685D03*
X408685D03*
X413685D03*
X418685D03*
X423685D03*
X428685D03*
X433685D03*
X438685D03*
X443685D03*
X448685D03*
X453685D03*
X458685D03*
X463685D03*
X468685D03*
X473685D03*
X478685D03*
X575412Y6000D03*
X570412D03*
X565412D03*
X560412D03*
X555412D03*
X550412D03*
X545412D03*
X540412D03*
X535412D03*
X530412D03*
X525412D03*
X520412D03*
X515412D03*
X510412D03*
X505412D03*
X500412D03*
X495412D03*
X490412D03*
X485412D03*
X501000Y1494000D03*
X503000Y1499000D03*
X494500Y1490500D03*
X574937Y1513685D03*
X569937D03*
X564937D03*
X559937D03*
X554937D03*
X549937D03*
X544937D03*
X539937D03*
X534937D03*
X529937D03*
X524937D03*
X483685Y1490063D03*
X488685D03*
X503244Y1504378D03*
Y1509378D03*
X504937Y1513685D03*
X509937D03*
X514937D03*
X519937D03*
X513917Y1447297D03*
X507917D03*
X519717D03*
X670412Y6000D03*
X665412D03*
X660412D03*
X655412D03*
X650412D03*
X645412D03*
X640412D03*
X635412D03*
X630412D03*
X625412D03*
X620412D03*
X615412D03*
X610412D03*
X605412D03*
X600412D03*
X595412D03*
X590412D03*
X585412D03*
X580412D03*
X669937Y1513685D03*
X659937D03*
X654937D03*
X649937D03*
X644937D03*
X639937D03*
X634937D03*
X629937D03*
X624937D03*
X619937D03*
X614937D03*
X609937D03*
X604937D03*
X599937D03*
X594937D03*
X589937D03*
X584937D03*
X579937D03*
X664937D03*
X765412Y6000D03*
X760412D03*
X755412D03*
X750412D03*
X745412D03*
X740412D03*
X735412D03*
X730412D03*
X725412D03*
X720412D03*
X715412D03*
X710412D03*
X705412D03*
X700412D03*
X695412D03*
X690412D03*
X685412D03*
X680412D03*
X675412D03*
X722000Y1503500D03*
X718500Y1500000D03*
X680500Y1503500D03*
X674937Y1513685D03*
X688012Y1499118D03*
X693012D03*
X698012D03*
X703012D03*
X708012D03*
X713012D03*
X724000Y1509500D03*
X725551Y1513685D03*
X730551D03*
X735551D03*
X740551D03*
X745551D03*
X750551D03*
X755551D03*
X760551D03*
X765551D03*
X678500Y1510500D03*
X777465Y93947D03*
Y88947D03*
Y83947D03*
Y78947D03*
Y73947D03*
Y68947D03*
Y63947D03*
Y58947D03*
Y53947D03*
Y48947D03*
Y43947D03*
Y38947D03*
Y33947D03*
Y28947D03*
Y23947D03*
Y18947D03*
Y13947D03*
X778000Y9500D03*
X775412Y6000D03*
X770412D03*
X777465Y183947D03*
Y178947D03*
Y173947D03*
Y168947D03*
Y163947D03*
Y158947D03*
Y153947D03*
Y148947D03*
Y143947D03*
Y138947D03*
Y133947D03*
Y128947D03*
Y123947D03*
Y118947D03*
Y113947D03*
Y108947D03*
Y103947D03*
Y98947D03*
X809500Y197500D03*
X805522Y195764D03*
X808961Y201678D03*
Y206678D03*
Y211678D03*
Y216678D03*
Y236678D03*
Y231678D03*
Y226678D03*
Y221678D03*
Y241678D03*
X779022Y190764D03*
X784022Y194764D03*
X800522Y195764D03*
X795522D03*
X790522D03*
X826843Y409096D03*
Y404296D03*
Y399496D03*
X822043D03*
Y404296D03*
Y409096D03*
X807643Y408996D03*
Y404196D03*
Y399396D03*
X802843D03*
Y404196D03*
Y408996D03*
X822400Y567100D03*
Y562300D03*
Y557500D03*
X817600D03*
Y562300D03*
Y567100D03*
X803200Y557400D03*
Y562200D03*
Y567000D03*
X798400Y557400D03*
Y562200D03*
Y567000D03*
X808300Y1197300D03*
X813100D03*
Y1206900D03*
Y1202100D03*
X808300D03*
Y1206900D03*
X794100Y1197300D03*
X789300D03*
X794100Y1202100D03*
Y1206900D03*
X789300Y1202100D03*
Y1206900D03*
X779500Y1491000D03*
X775000Y1495500D03*
X770551Y1513685D03*
X773528Y1510662D03*
Y1505662D03*
Y1500662D03*
X786803Y1490063D03*
X791803D03*
X796803D03*
X801803D03*
X806803D03*
X811803D03*
X816803D03*
X821803D03*
X826803D03*
X831803D03*
X836803D03*
X841803D03*
X846803D03*
X851803D03*
X856803D03*
X861803D03*
X887127Y254031D03*
X944200Y1083100D03*
X938900Y1103700D03*
X938800Y1109300D03*
X945200Y1398300D03*
Y1393500D03*
X950200Y1394500D03*
X866803Y1490063D03*
X871803D03*
X876803D03*
X881803D03*
X886803D03*
X891803D03*
X896803D03*
X901803D03*
X906803D03*
X911803D03*
X916803D03*
X921803D03*
X926803D03*
X931803D03*
X936803D03*
X941803D03*
X946803D03*
X951803D03*
X956803D03*
X1038200Y762300D03*
X1021194Y766883D03*
X1035594Y766983D03*
X1040394D03*
X1021194Y771683D03*
Y776483D03*
X1035594Y776583D03*
Y771783D03*
X1040394D03*
Y776583D03*
X1016394Y766883D03*
Y776483D03*
Y771683D03*
X997000Y1496000D03*
X993000Y1491500D03*
X961803Y1490063D03*
X966803D03*
X971803D03*
X976803D03*
X981803D03*
X986803D03*
X998126Y1503614D03*
Y1508614D03*
Y1513614D03*
X1003126D03*
X1008126D03*
X1013126D03*
X1018126D03*
X1023126D03*
X1028126D03*
X1033126D03*
X1038126D03*
X1043126D03*
X1048126D03*
X1053126D03*
X1068734Y195764D03*
X1064500Y197500D03*
X1065055Y201895D03*
Y206895D03*
Y211895D03*
Y216895D03*
Y226895D03*
Y231895D03*
Y236895D03*
Y241895D03*
Y221895D03*
X1148734Y195764D03*
X1143734D03*
X1138734D03*
X1133734D03*
X1128734D03*
X1123734D03*
X1118734D03*
X1113734D03*
X1103734D03*
X1098734D03*
X1093734D03*
X1088734D03*
X1083734D03*
X1078734D03*
X1073734D03*
X1075627Y374973D03*
X1075829Y380885D03*
X1119877Y408072D03*
Y403272D03*
Y398472D03*
X1124677D03*
Y403272D03*
Y408072D03*
X1100677Y407972D03*
Y403172D03*
Y398372D03*
X1105477D03*
Y403172D03*
Y407972D03*
X1076142Y386839D03*
X1128700Y1206500D03*
X1133500D03*
Y1201700D03*
X1128700D03*
X1133500Y1196900D03*
X1128700D03*
X1109600Y1197100D03*
X1114400D03*
X1109600Y1201900D03*
X1114400D03*
Y1206700D03*
X1109600D03*
X1087933Y1411323D03*
X1082933D03*
X1077933D03*
X1095567Y1426057D03*
X1117200Y1346700D03*
X1058126Y1513614D03*
X1061675Y1510352D03*
X1065210Y1506817D03*
X1066638Y1472408D03*
Y1467408D03*
Y1462408D03*
Y1457408D03*
Y1452408D03*
Y1447408D03*
Y1442408D03*
X1095567Y1431057D03*
Y1436057D03*
Y1441057D03*
Y1446057D03*
Y1451057D03*
Y1456057D03*
Y1461057D03*
Y1466057D03*
X1096039Y1505861D03*
X1099575Y1509397D03*
X1103110Y1512932D03*
X1107798Y1513685D03*
X1112798D03*
X1117798D03*
X1122798D03*
X1127798D03*
X1132798D03*
X1137798D03*
X1142798D03*
X1147798D03*
X1095567Y1471057D03*
X1066638Y1502408D03*
X1115000Y1485000D03*
X1118000Y1480500D03*
X1112000D03*
X1234500Y6000D03*
X1243844D03*
X1238844D03*
X1230409Y7565D03*
Y12565D03*
Y17565D03*
Y22565D03*
Y27565D03*
Y32565D03*
Y37565D03*
Y42565D03*
Y47565D03*
Y52565D03*
Y57565D03*
Y62565D03*
Y67565D03*
Y72565D03*
Y77565D03*
Y82565D03*
Y87565D03*
Y92565D03*
X1229000Y189500D03*
X1230409Y97565D03*
Y102565D03*
Y107565D03*
Y112565D03*
Y117565D03*
Y122565D03*
Y127565D03*
Y132565D03*
Y137565D03*
Y142565D03*
Y147565D03*
Y152565D03*
Y157565D03*
Y162565D03*
Y167565D03*
Y172565D03*
Y177565D03*
Y182565D03*
X1225000Y194000D03*
X1218734Y195764D03*
X1213734D03*
X1208734D03*
X1203734D03*
X1198734D03*
X1193734D03*
X1188734D03*
X1183734D03*
X1178734D03*
X1173734D03*
X1168734D03*
X1163734D03*
X1158734D03*
X1153734D03*
X1151100Y1179300D03*
X1155900D03*
X1151100Y1184100D03*
X1155900D03*
Y1188900D03*
X1151100D03*
X1245500Y1500500D03*
X1208000Y1502500D03*
X1234783Y1499118D03*
X1229783D03*
X1224783D03*
X1219783D03*
X1214783D03*
X1239783D03*
X1152798Y1513685D03*
X1157798D03*
X1162798D03*
X1167798D03*
X1172798D03*
X1177798D03*
X1182798D03*
X1187798D03*
X1192798D03*
X1197798D03*
X1202798D03*
X1205500Y1509000D03*
X1338844Y6000D03*
X1333844D03*
X1328844D03*
X1323844D03*
X1318844D03*
X1313844D03*
X1308844D03*
X1303844D03*
X1298844D03*
X1293844D03*
X1288844D03*
X1283844D03*
X1278844D03*
X1273844D03*
X1268844D03*
X1263844D03*
X1258844D03*
X1253844D03*
X1248844D03*
X1249000Y1504500D03*
X1328464Y1513685D03*
X1333464D03*
X1338464D03*
X1293464D03*
X1298464D03*
X1303464D03*
X1308464D03*
X1313464D03*
X1318464D03*
X1323464D03*
X1250500Y1510500D03*
X1253464Y1513685D03*
X1258464D03*
X1263464D03*
X1268464D03*
X1273464D03*
X1278464D03*
X1283464D03*
X1288464D03*
X1433844Y6000D03*
X1428844D03*
X1423844D03*
X1418844D03*
X1413844D03*
X1408844D03*
X1403844D03*
X1398844D03*
X1393844D03*
X1388844D03*
X1383844D03*
X1378844D03*
X1373844D03*
X1368844D03*
X1363844D03*
X1358844D03*
X1353844D03*
X1348844D03*
X1343844D03*
X1385474Y1429500D03*
X1380074D03*
X1383374Y1425000D03*
X1383674Y1419000D03*
X1433500Y1490500D03*
X1428500Y1494000D03*
X1403500Y1513500D03*
X1398500D03*
X1363464Y1513685D03*
X1368464D03*
X1373464D03*
X1378464D03*
X1383464D03*
X1388464D03*
X1393464D03*
X1353464D03*
X1358464D03*
X1343464D03*
X1348464D03*
X1408464D03*
X1413464D03*
X1418464D03*
X1423464D03*
X1425890Y1510111D03*
Y1505111D03*
Y1500111D03*
X1528844Y6000D03*
X1523844D03*
X1518844D03*
X1513844D03*
X1508844D03*
X1503844D03*
X1498844D03*
X1493844D03*
X1488844D03*
X1483844D03*
X1478844D03*
X1473844D03*
X1468844D03*
X1463844D03*
X1458844D03*
X1453844D03*
X1448844D03*
X1443844D03*
X1438844D03*
X1439716Y1490063D03*
X1444716D03*
X1449716D03*
X1454716D03*
X1459716D03*
X1464716D03*
X1469716D03*
X1474716D03*
X1479716D03*
X1484716D03*
X1489716D03*
X1494716D03*
X1499716D03*
X1504716D03*
X1509716D03*
X1514716D03*
X1519716D03*
X1524716D03*
X1529716D03*
X1623844Y6000D03*
X1618844D03*
X1613844D03*
X1608844D03*
X1603844D03*
X1598844D03*
X1593844D03*
X1588844D03*
X1583844D03*
X1578844D03*
X1573844D03*
X1568844D03*
X1563844D03*
X1558844D03*
X1553844D03*
X1548844D03*
X1543844D03*
X1538844D03*
X1533844D03*
X1534716Y1490063D03*
X1539716D03*
X1544716D03*
X1549716D03*
X1554716D03*
X1559716D03*
X1564716D03*
X1569716D03*
X1574716D03*
X1579716D03*
X1584716D03*
X1589716D03*
X1594716D03*
X1599716D03*
X1604716D03*
X1609716D03*
X1614716D03*
X1619716D03*
X1624716D03*
X1718844Y6000D03*
X1713844D03*
X1708844D03*
X1703844D03*
X1698844D03*
X1693844D03*
X1688844D03*
X1683844D03*
X1678844D03*
X1673844D03*
X1668844D03*
X1663844D03*
X1658844D03*
X1653844D03*
X1648844D03*
X1643844D03*
X1638844D03*
X1633844D03*
X1628844D03*
X1649500Y1497500D03*
X1646000Y1492000D03*
X1720968Y1513685D03*
X1715968D03*
X1710968D03*
X1705968D03*
X1700968D03*
X1695968D03*
X1690968D03*
X1685968D03*
X1680968D03*
X1670968D03*
X1675968D03*
X1629716Y1490063D03*
X1634716D03*
X1639716D03*
X1650488Y1504165D03*
Y1509165D03*
X1650968Y1513685D03*
X1655968D03*
X1660968D03*
X1665968D03*
X1813844Y6000D03*
X1808844D03*
X1803844D03*
X1798844D03*
X1793844D03*
X1788844D03*
X1783844D03*
X1778844D03*
X1773844D03*
X1768844D03*
X1763844D03*
X1758844D03*
X1753844D03*
X1748844D03*
X1743844D03*
X1738844D03*
X1733844D03*
X1728844D03*
X1723844D03*
X1814463Y449725D03*
Y454725D03*
X1804900Y451800D03*
X1809915Y461785D03*
Y446985D03*
Y456985D03*
Y442185D03*
X1799600Y451800D03*
X1794915Y461785D03*
Y446985D03*
Y456985D03*
Y442185D03*
X1751774Y430510D03*
X1753959Y450607D03*
X1766526Y1429400D03*
X1760326Y1429500D03*
X1763926Y1419000D03*
X1763626Y1425000D03*
X1786004Y1513500D03*
X1780968Y1513685D03*
X1775968D03*
X1770968D03*
X1765968D03*
X1760968D03*
X1755968D03*
X1750968D03*
X1745968D03*
X1740968D03*
X1796004Y1513500D03*
X1801004D03*
X1806004D03*
X1811004D03*
X1816004D03*
X1730968Y1513685D03*
X1725968D03*
X1791004Y1513500D03*
X1735968Y1513685D03*
X1913844Y6000D03*
X1908844D03*
X1903844D03*
X1898844D03*
X1893844D03*
X1888844D03*
X1883844D03*
X1878844D03*
X1873844D03*
X1868844D03*
X1863844D03*
X1858844D03*
X1853844D03*
X1848844D03*
X1843844D03*
X1838844D03*
X1833844D03*
X1828844D03*
X1823844D03*
X1818844D03*
X1838463Y454725D03*
Y449725D03*
X1819263D03*
Y454725D03*
X1833663D03*
Y449725D03*
X1828863D03*
Y454725D03*
X1824063D03*
Y449725D03*
X1912663Y888925D03*
Y883925D03*
X1869115Y876385D03*
Y891185D03*
Y881185D03*
Y895985D03*
X1873800Y886300D03*
X1884115Y876385D03*
X1898263Y883925D03*
Y888925D03*
X1903063D03*
Y883925D03*
X1907863D03*
Y888925D03*
X1884115Y891185D03*
Y881185D03*
Y895985D03*
X1893463Y888925D03*
Y883925D03*
X1879100Y886300D03*
X1888663Y888925D03*
Y883925D03*
X1828363Y884925D03*
X1869500Y1503500D03*
X1865500Y1500000D03*
X1829500Y1501500D03*
X1826500Y1506500D03*
X1855256Y1499118D03*
X1850256D03*
X1845256D03*
X1840256D03*
X1826040Y1513315D03*
X1821040D03*
X1835256Y1499118D03*
X1860256D03*
X1871157Y1509110D03*
X1871582Y1513685D03*
X1876582D03*
X1881582D03*
X1886582D03*
X1891582D03*
X1896582D03*
X1901582D03*
X1906582D03*
X1911582D03*
X1928843Y8985D03*
Y93985D03*
Y88985D03*
Y83985D03*
Y78985D03*
Y73985D03*
Y68985D03*
Y63985D03*
Y58985D03*
Y53985D03*
Y48985D03*
Y43985D03*
Y38985D03*
Y28985D03*
Y23985D03*
Y18985D03*
Y13985D03*
Y33985D03*
X1923844Y6000D03*
X1918844D03*
X1928843Y98985D03*
Y188985D03*
Y183985D03*
Y178985D03*
Y173985D03*
Y168985D03*
Y163985D03*
Y158985D03*
Y153985D03*
Y148985D03*
Y143985D03*
Y138985D03*
Y133985D03*
Y128985D03*
Y123985D03*
Y118985D03*
Y113985D03*
Y108985D03*
Y103985D03*
Y283985D03*
Y278985D03*
Y273985D03*
Y268985D03*
Y263985D03*
Y258985D03*
Y253985D03*
Y248985D03*
Y243985D03*
Y238985D03*
Y233985D03*
Y228985D03*
Y223985D03*
Y218985D03*
Y213985D03*
Y208985D03*
Y203985D03*
Y198985D03*
Y193985D03*
Y378985D03*
Y373985D03*
Y368985D03*
Y363985D03*
Y358985D03*
Y353985D03*
Y348985D03*
Y343985D03*
Y338985D03*
Y333985D03*
Y328985D03*
Y323985D03*
Y318985D03*
Y313985D03*
Y308985D03*
Y303985D03*
Y298985D03*
Y293985D03*
Y288985D03*
Y418985D03*
Y433985D03*
Y428985D03*
Y423985D03*
Y473985D03*
Y468985D03*
Y463985D03*
Y458985D03*
Y453985D03*
Y448985D03*
Y443985D03*
Y438985D03*
Y413985D03*
Y408985D03*
Y403985D03*
Y398985D03*
Y393985D03*
Y388985D03*
Y383985D03*
Y568985D03*
Y563985D03*
Y558985D03*
Y553985D03*
Y548985D03*
Y543985D03*
Y538985D03*
Y533985D03*
Y528985D03*
Y523985D03*
Y518985D03*
Y513985D03*
Y508985D03*
Y503985D03*
Y498985D03*
Y493985D03*
Y488985D03*
Y483985D03*
Y478985D03*
Y663985D03*
Y658985D03*
Y653985D03*
Y648985D03*
Y643985D03*
Y638985D03*
Y633985D03*
Y628985D03*
Y623985D03*
Y618985D03*
Y613985D03*
Y608985D03*
Y603985D03*
Y598985D03*
Y593985D03*
Y588985D03*
Y583985D03*
Y578985D03*
Y573985D03*
Y758985D03*
Y753985D03*
Y748985D03*
Y743985D03*
Y738985D03*
Y733985D03*
Y728985D03*
Y723985D03*
Y718985D03*
Y713985D03*
Y708985D03*
Y703985D03*
Y698985D03*
Y693985D03*
Y688985D03*
Y683985D03*
Y678985D03*
Y673985D03*
Y668985D03*
Y853985D03*
Y848985D03*
Y843985D03*
Y838985D03*
Y833985D03*
Y828985D03*
Y823985D03*
Y818985D03*
Y813985D03*
Y808985D03*
Y803985D03*
Y798985D03*
Y793985D03*
Y788985D03*
Y783985D03*
Y778985D03*
Y773985D03*
Y768985D03*
Y763985D03*
Y918985D03*
Y913985D03*
Y908985D03*
Y903985D03*
Y898985D03*
Y893985D03*
Y888985D03*
Y883985D03*
Y878985D03*
Y873985D03*
Y868985D03*
Y863985D03*
Y858985D03*
Y948985D03*
Y943985D03*
Y938985D03*
Y933985D03*
Y928985D03*
Y923985D03*
Y1043985D03*
Y1038985D03*
Y1033985D03*
Y1028985D03*
Y1023985D03*
Y1018985D03*
Y1013985D03*
Y1008985D03*
Y1003985D03*
Y998985D03*
Y993985D03*
Y988985D03*
Y983985D03*
Y978985D03*
Y973985D03*
Y968985D03*
Y963985D03*
Y958985D03*
Y953985D03*
Y1143985D03*
Y1138985D03*
Y1133985D03*
Y1128985D03*
Y1123985D03*
Y1118985D03*
Y1113985D03*
Y1108985D03*
Y1103985D03*
Y1098985D03*
Y1093985D03*
Y1088985D03*
Y1083985D03*
Y1078985D03*
Y1073985D03*
Y1068985D03*
Y1063985D03*
Y1058985D03*
Y1053985D03*
Y1048985D03*
Y1238985D03*
Y1233985D03*
Y1228985D03*
Y1223985D03*
Y1218985D03*
Y1213985D03*
Y1208985D03*
Y1203985D03*
Y1198985D03*
Y1193985D03*
Y1188985D03*
Y1183985D03*
Y1178985D03*
Y1173985D03*
Y1168985D03*
Y1163985D03*
Y1158985D03*
Y1153985D03*
Y1148985D03*
Y1288985D03*
Y1293985D03*
Y1298985D03*
Y1303985D03*
Y1308985D03*
Y1313985D03*
Y1318985D03*
Y1323985D03*
Y1328985D03*
Y1333985D03*
Y1283985D03*
Y1278985D03*
Y1273985D03*
Y1268985D03*
Y1263985D03*
Y1258985D03*
Y1253985D03*
Y1248985D03*
Y1243985D03*
Y1348985D03*
Y1353985D03*
Y1358985D03*
Y1363985D03*
Y1368985D03*
Y1373985D03*
Y1378985D03*
Y1383985D03*
Y1388985D03*
Y1393985D03*
Y1398985D03*
Y1403985D03*
Y1408985D03*
Y1413985D03*
Y1418985D03*
Y1423985D03*
Y1428985D03*
Y1338985D03*
Y1343985D03*
Y1448985D03*
Y1443985D03*
Y1433985D03*
Y1438985D03*
X1920000Y1458000D03*
X1917500Y1463500D03*
X1916582Y1513685D03*
X1917031Y1509134D03*
Y1504134D03*
Y1499134D03*
Y1494134D03*
Y1489134D03*
Y1484134D03*
Y1479134D03*
Y1474134D03*
Y1469134D03*
X1926500Y1455000D03*
G54D15*
X90709Y1485118D03*
X80709D03*
X70709D03*
X711181D03*
X701181D03*
X691181D03*
X1237953D03*
X1227953D03*
X1217953D03*
X1858425D03*
X1848425D03*
X1838425D03*
G54D19*
X111024Y188130D03*
Y640886D03*
Y1093642D03*
X235236Y188130D03*
Y640886D03*
Y1093642D03*
X359449Y188130D03*
Y640886D03*
Y1093642D03*
X483661Y188130D03*
Y640886D03*
Y1093642D03*
X607874Y188130D03*
Y640886D03*
Y1093642D03*
X732087Y188130D03*
Y640886D03*
Y1093642D03*
X1281693Y188130D03*
Y640886D03*
Y1093642D03*
X1405906Y188130D03*
Y640886D03*
Y1093642D03*
X1530118Y188130D03*
Y640886D03*
Y1093642D03*
X1654331Y188130D03*
Y640886D03*
Y1093642D03*
X1778543Y188130D03*
Y640886D03*
Y1093642D03*
X1902756Y188130D03*
Y640886D03*
Y1093642D03*
G54D16*
X127988Y67319D03*
Y71319D03*
Y76319D03*
Y80319D03*
X134983Y65269D03*
Y61269D03*
Y56769D03*
Y52769D03*
X127988Y520075D03*
Y524075D03*
Y529075D03*
Y533075D03*
X134983Y518025D03*
Y514025D03*
Y509525D03*
Y505525D03*
X127988Y972831D03*
Y976831D03*
Y981831D03*
Y985831D03*
X134983Y970781D03*
Y966781D03*
Y962281D03*
Y958281D03*
X252200Y67319D03*
Y71319D03*
Y76319D03*
Y80319D03*
X259195Y65269D03*
Y61269D03*
Y56769D03*
Y52769D03*
X252200Y520075D03*
Y524075D03*
Y529075D03*
Y533075D03*
X259195Y518025D03*
Y514025D03*
Y509525D03*
Y505525D03*
X252200Y972831D03*
Y976831D03*
Y981831D03*
Y985831D03*
X259195Y970781D03*
Y966781D03*
Y962281D03*
Y958281D03*
X376413Y67319D03*
Y71319D03*
Y76319D03*
Y80319D03*
X383408Y65269D03*
Y61269D03*
Y56769D03*
Y52769D03*
X376413Y520075D03*
Y524075D03*
Y529075D03*
Y533075D03*
X383408Y518025D03*
Y514025D03*
Y509525D03*
Y505525D03*
X376413Y972831D03*
Y976831D03*
Y981831D03*
Y985831D03*
X383408Y970781D03*
Y966781D03*
Y962281D03*
Y958281D03*
X500625Y67319D03*
Y71319D03*
Y76319D03*
Y80319D03*
X507620Y65269D03*
Y61269D03*
Y56769D03*
Y52769D03*
X500625Y520075D03*
Y524075D03*
Y529075D03*
Y533075D03*
X507620Y518025D03*
Y514025D03*
Y509525D03*
Y505525D03*
X500625Y972831D03*
Y976831D03*
Y981831D03*
Y985831D03*
X507620Y970781D03*
Y966781D03*
Y962281D03*
Y958281D03*
X624838Y67319D03*
Y71319D03*
Y76319D03*
Y80319D03*
X631833Y65269D03*
Y61269D03*
Y56769D03*
Y52769D03*
X624838Y520075D03*
Y524075D03*
Y529075D03*
Y533075D03*
X631833Y518025D03*
Y514025D03*
Y509525D03*
Y505525D03*
X624838Y972831D03*
Y976831D03*
Y981831D03*
Y985831D03*
X631833Y970781D03*
Y966781D03*
Y962281D03*
Y958281D03*
X749051Y67319D03*
Y71319D03*
Y76319D03*
Y80319D03*
X756046Y65269D03*
Y61269D03*
Y56769D03*
Y52769D03*
X749051Y520075D03*
Y524075D03*
Y529075D03*
Y533075D03*
X756046Y518025D03*
Y514025D03*
Y509525D03*
Y505525D03*
X749051Y972831D03*
Y976831D03*
Y981831D03*
Y985831D03*
X756046Y970781D03*
Y966781D03*
Y962281D03*
Y958281D03*
X1279400Y68650D03*
X1275400D03*
X1270400D03*
X1266400D03*
X1252750Y53650D03*
X1256750D03*
X1261250D03*
X1265250D03*
X1279400Y521406D03*
X1275400D03*
X1270400D03*
X1266400D03*
X1252750Y506406D03*
X1256750D03*
X1261250D03*
X1265250D03*
X1273975Y972831D03*
Y976831D03*
Y981831D03*
Y985831D03*
X1257490Y970361D03*
Y966361D03*
Y961861D03*
Y957861D03*
X1403613Y68650D03*
X1399613D03*
X1394613D03*
X1390613D03*
X1376963Y53650D03*
X1380963D03*
X1385463D03*
X1389463D03*
X1403613Y521406D03*
X1399613D03*
X1394613D03*
X1390613D03*
X1376963Y506406D03*
X1380963D03*
X1385463D03*
X1389463D03*
X1398188Y972831D03*
Y976831D03*
Y981831D03*
Y985831D03*
X1381663Y970381D03*
Y966381D03*
Y961881D03*
Y957881D03*
X1527825Y68650D03*
X1523825D03*
X1518825D03*
X1514825D03*
X1501175Y53650D03*
X1505175D03*
X1509675D03*
X1513675D03*
X1527825Y521406D03*
X1523825D03*
X1518825D03*
X1514825D03*
X1501175Y506406D03*
X1505175D03*
X1509675D03*
X1513675D03*
X1522400Y972831D03*
Y976831D03*
Y981831D03*
Y985831D03*
X1505875Y970321D03*
Y966321D03*
Y961821D03*
Y957821D03*
X1625388Y53650D03*
Y506406D03*
X1652038Y68650D03*
X1648038D03*
X1643038D03*
X1639038D03*
X1629388Y53650D03*
X1633888D03*
X1637888D03*
X1652038Y521406D03*
X1648038D03*
X1643038D03*
X1639038D03*
X1629388Y506406D03*
X1633888D03*
X1637888D03*
X1646613Y972831D03*
Y976831D03*
Y981831D03*
Y985831D03*
X1630088Y970881D03*
Y966881D03*
Y962381D03*
Y958381D03*
X1776250Y68650D03*
X1772250D03*
X1767250D03*
X1763250D03*
X1749600Y53650D03*
X1753600D03*
X1758100D03*
X1762100D03*
X1776250Y521406D03*
X1772250D03*
X1767250D03*
X1763250D03*
X1749600Y506406D03*
X1753600D03*
X1758100D03*
X1762100D03*
X1770825Y972831D03*
Y976831D03*
Y981831D03*
Y985831D03*
X1754340Y970361D03*
Y966361D03*
Y961861D03*
Y957861D03*
X1900463Y68650D03*
X1896463D03*
X1891463D03*
X1887463D03*
X1873813Y53650D03*
X1877813D03*
X1882313D03*
X1886313D03*
X1900463Y521406D03*
X1896463D03*
X1891463D03*
X1887463D03*
X1873813Y506406D03*
X1877813D03*
X1882313D03*
X1886313D03*
X1895038Y972831D03*
Y976831D03*
Y981831D03*
Y985831D03*
X1878553Y970361D03*
Y966361D03*
Y961861D03*
Y957861D03*
G54D17*
X111024Y39508D03*
Y492264D03*
Y945020D03*
X235236Y39508D03*
Y492264D03*
Y945020D03*
X359449Y39508D03*
Y492264D03*
Y945020D03*
X483661Y39508D03*
Y492264D03*
Y945020D03*
X607874Y39508D03*
Y492264D03*
Y945020D03*
X732087Y39508D03*
Y492264D03*
Y945020D03*
X1281693Y39508D03*
Y492264D03*
Y945020D03*
X1405906Y39508D03*
Y492264D03*
Y945020D03*
X1530118Y39508D03*
Y492264D03*
Y945020D03*
X1654331Y39508D03*
Y492264D03*
Y945020D03*
X1778543Y39508D03*
Y492264D03*
Y945020D03*
X1902756Y39508D03*
Y492264D03*
Y945020D03*
G54D35*
X974015Y284449D03*
X986614D03*
X1002362D03*
X1014960D03*
X1030709D03*
X1043307D03*
X1002362Y261812D03*
X1014960D03*
X1030709D03*
X1043307D03*
X974015Y278544D03*
X1002362D03*
X1030709D03*
X1002362Y267717D03*
X1030709D03*
X1002362Y255906D03*
X1030709D03*
X986614Y278544D03*
X1014960D03*
X1043307D03*
X1014960Y267717D03*
X1043307D03*
X1014960Y255906D03*
X1043307D03*
X974015Y307087D03*
X986614D03*
X1002362D03*
X1014960D03*
X1030709D03*
X1043307D03*
X974015Y312993D03*
X1002362D03*
X1030709D03*
X974015Y301182D03*
X1002362D03*
X1030709D03*
X974015Y290355D03*
X1002362D03*
X1030709D03*
X986614Y312993D03*
X1014960D03*
X1043307D03*
X986614Y301182D03*
X1014960D03*
X1043307D03*
X986614Y290355D03*
X1014960D03*
X1043307D03*
X1101405Y1120040D03*
X1119633D03*
X1108098D03*
X1126326D03*
G54D28*
X384055Y1330472D03*
Y1320472D03*
X354055Y1330472D03*
X364055D03*
X354055Y1320472D03*
X364055D03*
X324055Y1330472D03*
X334055D03*
X324055Y1320472D03*
X334055D03*
X304055Y1330472D03*
Y1320472D03*
X294055Y1330472D03*
Y1320472D03*
X384055Y1340472D03*
Y1350472D03*
X354055Y1340472D03*
Y1350472D03*
X364055Y1340472D03*
Y1350472D03*
X324055Y1340472D03*
Y1350472D03*
X334055Y1340472D03*
Y1350472D03*
X304055D03*
Y1340472D03*
X294055Y1350472D03*
Y1340472D03*
X394055Y1330472D03*
Y1320472D03*
Y1340472D03*
Y1350472D03*
G54D34*
X836862Y637500D03*
X935477Y524023D03*
X938338Y529107D03*
X938579Y551379D03*
X938623Y556600D03*
X904484Y786109D03*
X1050818Y1311189D03*
Y1316589D03*
X1045418Y1321989D03*
X1050818D03*
X1034618Y1311189D03*
X1040018D03*
X1045418D03*
X1040018Y1316589D03*
X1034618D03*
X1040018Y1321989D03*
X1031600Y1335100D03*
X1037200Y1335000D03*
X1034618Y1321989D03*
X1034600Y1349600D03*
X1042400Y1349500D03*
X1037540Y1344964D03*
X1034799Y1340183D03*
X1044700Y1335500D03*
X1043300Y1342500D03*
X1048000Y1346100D03*
X1037111Y1372380D03*
X1039988Y1367352D03*
X1044400Y1363100D03*
X1036900Y1362600D03*
X1034380Y1367469D03*
X1031300Y1362700D03*
X1042100Y1377100D03*
X1034300Y1377200D03*
X1047401Y1375084D03*
X1061618Y1316589D03*
X1056218Y1311189D03*
X1061618D03*
X1056218Y1316589D03*
X1060218Y1321989D03*
X1066491Y1319983D03*
X1066407Y1313972D03*
X1596400Y135600D03*
Y131100D03*
Y126100D03*
G54D13*
X56750Y62000D03*
X64250Y87500D03*
X50000Y105500D03*
X54500D03*
X59000D03*
X64250Y540000D03*
X50000Y558000D03*
X54500D03*
X59000D03*
X26300Y873700D03*
Y864100D03*
Y868900D03*
X21500Y873700D03*
Y864100D03*
Y868900D03*
X59000Y1011000D03*
X54500D03*
X50000D03*
X64250Y993000D03*
X183500Y75450D03*
Y80250D03*
X178500Y80000D03*
X127600Y437500D03*
Y432700D03*
X122800Y437500D03*
Y432700D03*
X127600Y427900D03*
X122800D03*
X188250Y540000D03*
X182300Y558600D03*
X173600Y554400D03*
Y558600D03*
X178100D03*
X183500Y1011000D03*
X179000D03*
X174500D03*
X188750Y993000D03*
X217000Y38250D03*
X198800Y34000D03*
X203078Y33972D03*
X311800Y83700D03*
X293700Y105500D03*
X298500D03*
X302999Y105501D03*
X312750Y536300D03*
X299104Y556943D03*
X303604D03*
X308104D03*
X307500Y1011000D03*
X303000D03*
X298500D03*
X312750Y993000D03*
X465500Y38250D03*
X425500Y41250D03*
X430500D03*
X434804Y41242D03*
X444663Y32417D03*
X440400Y32400D03*
X430083Y122357D03*
X436750Y538400D03*
X422500Y558000D03*
X427000D03*
X431500D03*
Y1011000D03*
X427000D03*
X422500D03*
X436750Y993000D03*
X474055Y1330472D03*
X484055D03*
X474055Y1320472D03*
X484055D03*
X444055Y1330472D03*
X454055D03*
X444055Y1320472D03*
X454055D03*
X414055Y1330472D03*
X424055D03*
X414055Y1320472D03*
X424055D03*
X474055Y1340472D03*
Y1350472D03*
X484055Y1340472D03*
Y1350472D03*
X444055Y1340472D03*
Y1350472D03*
X454055Y1340472D03*
Y1350472D03*
X414055Y1340472D03*
Y1350472D03*
X424055Y1340472D03*
Y1350472D03*
X462000Y1382985D03*
Y1372985D03*
Y1362985D03*
X474000Y1382985D03*
Y1372985D03*
Y1362985D03*
X426000D03*
X450000Y1372985D03*
Y1382985D03*
X414000Y1372985D03*
X450000Y1362985D03*
X438000Y1372985D03*
X414000Y1362985D03*
X438000D03*
X426000Y1372985D03*
X438000Y1382985D03*
X414000D03*
X426000D03*
X561250Y87500D03*
X547000Y105500D03*
X551500D03*
X556000D03*
X561250Y540000D03*
X546500Y572000D03*
X551044Y572149D03*
X555321Y572375D03*
X556000Y1011000D03*
X551500D03*
X547000D03*
X561250Y993000D03*
X498000Y1332985D03*
X510000Y1344485D03*
X498000Y1352985D03*
X522000Y1344485D03*
X498000Y1342985D03*
X510000Y1354485D03*
X522000D03*
X510000Y1364485D03*
X522000D03*
X510000Y1374485D03*
Y1384485D03*
X522000Y1374485D03*
Y1384485D03*
X498000Y1382985D03*
Y1372985D03*
X486000Y1382985D03*
Y1372985D03*
X498000Y1362985D03*
X486000D03*
X670500Y80000D03*
X672018Y557014D03*
X671000Y1011000D03*
X581800Y1376500D03*
Y1384400D03*
Y1392300D03*
Y1360700D03*
Y1368600D03*
Y1352800D03*
Y1344900D03*
X589700Y1392300D03*
Y1400200D03*
Y1344900D03*
Y1352800D03*
Y1384400D03*
Y1376500D03*
Y1368600D03*
Y1360700D03*
X597600Y1400200D03*
Y1408100D03*
Y1360700D03*
Y1368600D03*
Y1392300D03*
Y1376500D03*
Y1384400D03*
Y1352800D03*
Y1344900D03*
X629200D03*
X621300D03*
X613400D03*
X605500D03*
Y1360700D03*
X613400D03*
X621300D03*
X629200D03*
X605500Y1352800D03*
X613400D03*
X621300D03*
X629200D03*
Y1368600D03*
Y1376500D03*
X605500Y1408100D03*
Y1400200D03*
Y1392300D03*
Y1384400D03*
Y1376500D03*
Y1368600D03*
X613400Y1400200D03*
Y1392300D03*
Y1384400D03*
Y1376500D03*
Y1368600D03*
X621300Y1376500D03*
Y1368600D03*
X613400Y1408100D03*
X680500Y80250D03*
X675500Y80000D03*
X714000Y38250D03*
X695600Y34000D03*
X699932Y34034D03*
X685250Y540000D03*
X680902Y557860D03*
X676402D03*
X680000Y1011000D03*
X675500D03*
X685250Y993000D03*
X862205Y282283D03*
X848032D03*
X833859D03*
X862205Y268110D03*
X848032D03*
X833859D03*
X862205Y253937D03*
X848032D03*
X833859D03*
X855118Y272835D03*
X840945D03*
X826772D03*
X862205Y310630D03*
X848032D03*
X833859D03*
X862205Y296457D03*
X848032D03*
X833859D03*
X855118Y315354D03*
X840945D03*
X826772D03*
X855118Y301181D03*
X840945D03*
X826772D03*
X855118Y287008D03*
X840945D03*
X826772D03*
X860519Y428234D03*
X860716Y417600D03*
X850947Y417592D03*
X815148Y654937D03*
X818113Y814998D03*
X834200Y796220D03*
X810700Y772000D03*
Y781000D03*
X822463Y920345D03*
X861300Y895300D03*
X819000Y896100D03*
X817337Y886075D03*
X839970Y981470D03*
X834470D03*
X826470D03*
X876378Y282283D03*
Y268110D03*
Y253937D03*
X869292Y272835D03*
X911811Y306299D03*
X876378Y310630D03*
Y296457D03*
X869292Y315354D03*
Y301181D03*
Y287008D03*
X871591Y431161D03*
X955000Y540800D03*
X956100Y516500D03*
X874706Y752583D03*
X911080Y857420D03*
X881216Y813813D03*
X910807Y766589D03*
X876256Y798895D03*
X874500Y779100D03*
X927260Y922470D03*
X909760Y925445D03*
X922760Y922470D03*
X958256Y894438D03*
X930310Y858550D03*
X879770Y868369D03*
X1012000Y371369D03*
X1015537Y365911D03*
X974530Y559550D03*
X974550Y563690D03*
X971420Y537950D03*
X975910Y537770D03*
X995213Y529837D03*
X998905Y529824D03*
X986638Y519684D03*
X963870Y754152D03*
X1050774Y815327D03*
X1050650Y825420D03*
X1022838Y829101D03*
X1042545Y832026D03*
X1015950Y838000D03*
X1026932Y841614D03*
X1050082Y843729D03*
X993400Y833250D03*
X1027524Y948954D03*
X1039500Y891100D03*
X1037110Y859471D03*
X972042Y884600D03*
X985542Y882900D03*
X989742D03*
X1017618Y1470865D03*
X993830Y1471364D03*
X1137600Y527100D03*
X1137446Y541317D03*
Y555490D03*
Y569663D03*
Y698798D03*
Y712971D03*
Y727144D03*
Y741317D03*
Y755490D03*
Y769663D03*
Y783836D03*
Y798010D03*
Y812183D03*
Y826356D03*
Y840529D03*
Y854703D03*
X1057400Y771600D03*
X1057600Y776500D03*
X1067200Y786500D03*
X1062400D03*
Y781500D03*
X1057600Y786500D03*
Y781500D03*
X1067200Y791500D03*
X1062400D03*
X1067200Y796500D03*
X1062400D03*
X1057600D03*
Y791500D03*
X1137446Y868876D03*
Y883049D03*
Y897222D03*
Y911396D03*
Y925569D03*
Y939742D03*
X1297000Y68500D03*
X1319100Y47400D03*
X1322500Y113500D03*
X1317500D03*
X1327000D03*
X1323000Y566500D03*
X1318000D03*
X1328000D03*
X1300100Y530000D03*
X1326500Y514000D03*
X1323000Y1019000D03*
X1318000D03*
X1328000D03*
X1300900Y981800D03*
X1326500Y966500D03*
X1435750Y73750D03*
X1424500Y529100D03*
X1424400Y982000D03*
X1450500Y61000D03*
X1447000Y113500D03*
X1442000D03*
X1452000D03*
X1447000Y566500D03*
X1442000D03*
X1452000D03*
X1450500Y514000D03*
X1447000Y1019000D03*
X1442000D03*
X1452000D03*
X1450500Y966500D03*
X1548279Y69309D03*
X1575400Y50750D03*
X1571500Y566500D03*
X1566500D03*
X1576500D03*
X1548400Y528800D03*
X1575000Y514000D03*
X1571500Y1019000D03*
X1566500D03*
X1576500D03*
X1575000Y966500D03*
X1548900Y981500D03*
X1699000Y61000D03*
X1672900Y76400D03*
X1690400Y114100D03*
X1695400D03*
X1700400D03*
X1667359Y434407D03*
Y439207D03*
Y429607D03*
X1662559D03*
Y434407D03*
Y439207D03*
X1695500Y566500D03*
X1690500D03*
X1700500D03*
X1673200Y529000D03*
X1699000Y514000D03*
X1695500Y1019000D03*
X1690500D03*
X1700500D03*
X1699000Y966500D03*
X1672800Y981200D03*
X1814500Y566500D03*
X1797400Y528800D03*
X1741159Y873707D03*
X1736359D03*
X1741159Y864107D03*
X1736359D03*
X1741159Y868907D03*
X1736359D03*
X1814500Y1019000D03*
X1796900Y981100D03*
X1845900Y77300D03*
X1840900D03*
X1850800Y77200D03*
X1859050Y19000D03*
X1823500Y113500D03*
X1819134Y109132D03*
X1819000Y113500D03*
X1819500Y566500D03*
X1824500D03*
X1855750Y540000D03*
X1839750Y530250D03*
X1841500Y558000D03*
X1846000D03*
X1850500D03*
X1823000Y514000D03*
X1850500Y1011000D03*
X1846000D03*
X1841500D03*
X1819500Y1019000D03*
X1824500D03*
X1855750Y993000D03*
X1823000Y966500D03*
X1839750Y983000D03*
G54D22*
X102263Y919025D03*
X200090Y481289D03*
X1742859Y484707D03*
X1817263Y919025D03*
G54D23*
X184252Y1445275D03*
Y1466929D03*
X167716Y1445275D03*
Y1466929D03*
X233858Y1445275D03*
Y1466929D03*
X217322Y1445275D03*
Y1466929D03*
X200787Y1445275D03*
Y1466929D03*
X581102Y1445275D03*
Y1466929D03*
X564567Y1445275D03*
Y1466929D03*
X548031Y1445275D03*
Y1466929D03*
X614173Y1445275D03*
Y1466929D03*
X597637Y1445275D03*
Y1466929D03*
X1331496Y1445275D03*
Y1466929D03*
X1314960Y1445275D03*
Y1466929D03*
X1381102Y1445275D03*
Y1466929D03*
X1364566Y1445275D03*
Y1466929D03*
X1348031Y1445275D03*
Y1466929D03*
X1711811Y1445275D03*
Y1466929D03*
X1695275Y1445275D03*
Y1466929D03*
X1761417Y1445275D03*
Y1466929D03*
X1744881Y1445275D03*
Y1466929D03*
X1728346Y1445275D03*
Y1466929D03*
G54D10*
X59400Y32600D03*
X63374Y1454500D03*
X390757Y1511515D03*
X812347Y17406D03*
X885639Y1511515D03*
X1187163Y158305D03*
X1538001Y1511515D03*
X1869500Y1461500D03*
G54D18*
X173228Y55118D03*
X421653Y94488D03*
X670078Y55118D03*
X1343701D03*
X1592126Y94488D03*
X1840551Y55118D03*
G54D29*
X503248Y715748D03*
X1673917Y262992D03*
G54D26*
X246535Y1320472D03*
X531535D03*
G54D27*
X266535D03*
X511535D03*
G54D24*
X167716Y1495669D03*
X233858D03*
X548031D03*
X614173D03*
X1314960D03*
X1381102D03*
X1695275D03*
X1761417D03*
G54D20*
X173228Y122047D03*
X670079D03*
X1343701Y122046D03*
X1840551D03*
G54D36*
X1104528Y1162257D03*
G54D14*
X53250Y518000D03*
Y971000D03*
X176439Y524992D03*
X178200Y977700D03*
X301750Y65500D03*
Y518000D03*
X302100Y978200D03*
X429210Y512992D03*
X426300Y976800D03*
X550250Y65500D03*
Y518000D03*
X550700Y979500D03*
X674250Y518000D03*
X675400Y980500D03*
X855100Y258531D03*
X841000D03*
X826700D03*
X869300D03*
X878740Y643190D03*
Y651190D03*
X1003591Y552081D03*
X996998Y539555D03*
X990200Y544250D03*
X971197Y775799D03*
X1091089Y520057D03*
X1105262D03*
X1119435D03*
X1133609D03*
X1095026Y527143D03*
X1109199D03*
X1123372D03*
X1091089Y534230D03*
X1105262D03*
X1119435D03*
X1133609D03*
X1095026Y541317D03*
X1109199D03*
X1123372D03*
X1091089Y548403D03*
X1105262D03*
X1119435D03*
X1133609D03*
X1095026Y555490D03*
X1109199D03*
X1123372D03*
X1091089Y562576D03*
X1105262D03*
X1119435D03*
X1133609D03*
X1095026Y569663D03*
X1109199D03*
X1123372D03*
X1091089Y691711D03*
Y705884D03*
Y720057D03*
Y734230D03*
Y748403D03*
Y762577D03*
X1105262Y691711D03*
Y705884D03*
Y720057D03*
Y734230D03*
Y748403D03*
Y762577D03*
X1119435Y691711D03*
Y705884D03*
Y720057D03*
Y734230D03*
Y748403D03*
Y762577D03*
X1133609Y691711D03*
Y705884D03*
Y720057D03*
Y734230D03*
Y748403D03*
Y762577D03*
X1095026Y698797D03*
Y712970D03*
Y727144D03*
Y741317D03*
Y755490D03*
X1109199Y698797D03*
Y712970D03*
Y727144D03*
Y741317D03*
Y755490D03*
X1123372Y698797D03*
Y712970D03*
Y727144D03*
Y741317D03*
Y755490D03*
X1091089Y776750D03*
Y790923D03*
Y805096D03*
Y819270D03*
Y833443D03*
Y847616D03*
X1105262Y776750D03*
Y790923D03*
Y805096D03*
Y819270D03*
Y833443D03*
Y847616D03*
X1119435Y776750D03*
Y790923D03*
Y805096D03*
Y819270D03*
Y833443D03*
Y847616D03*
X1133609Y776750D03*
Y790923D03*
Y805096D03*
Y819270D03*
Y833443D03*
Y847616D03*
X1095026Y769663D03*
Y783836D03*
Y798010D03*
Y812183D03*
Y826356D03*
Y840529D03*
Y854703D03*
X1109199Y769663D03*
Y783836D03*
Y798010D03*
Y812183D03*
Y826356D03*
Y840529D03*
Y854703D03*
X1123372Y769663D03*
Y783836D03*
Y798010D03*
Y812183D03*
Y826356D03*
Y840529D03*
Y854703D03*
X1091089Y861789D03*
Y875962D03*
Y890136D03*
Y904309D03*
Y918482D03*
Y932655D03*
X1105262Y861789D03*
Y875962D03*
Y890136D03*
Y904309D03*
Y918482D03*
Y932655D03*
X1119435Y861789D03*
Y875962D03*
Y890136D03*
Y904309D03*
Y918482D03*
Y932655D03*
X1133609Y861789D03*
Y875962D03*
Y890136D03*
Y904309D03*
Y918482D03*
Y932655D03*
X1095026Y868876D03*
Y883049D03*
Y897222D03*
Y911396D03*
Y925569D03*
Y939742D03*
X1109199Y868876D03*
Y883049D03*
Y897222D03*
Y911396D03*
Y925569D03*
Y939742D03*
X1123372Y868876D03*
Y883049D03*
Y897222D03*
Y911396D03*
Y925569D03*
Y939742D03*
X1101405Y1132638D03*
X1119633D03*
X1108098D03*
X1126326D03*
X1799094Y82033D03*
X1860500Y38100D03*
G54D25*
X200819Y74819D03*
X697787Y74488D03*
X826843Y419764D03*
Y424564D03*
Y429364D03*
X802843Y419664D03*
X807643D03*
X822043Y419764D03*
X802843Y429264D03*
Y424464D03*
X807643D03*
Y429264D03*
X822043Y429364D03*
Y424564D03*
X822400Y587368D03*
Y582568D03*
X817600D03*
Y587368D03*
X803200Y587268D03*
Y582468D03*
X798400D03*
Y587268D03*
X822400Y577768D03*
X817600D03*
X803200Y577668D03*
X798400D03*
X842270Y936402D03*
X808300Y1227168D03*
Y1222368D03*
X813100D03*
Y1227168D03*
X794100D03*
Y1222368D03*
X789300D03*
Y1227168D03*
X813100Y1217568D03*
X808300D03*
X789300D03*
X794100D03*
X953000Y842400D03*
X948500D03*
X891600Y980000D03*
X888000D03*
X886400Y976500D03*
X893600D03*
X897200D03*
X895200Y980000D03*
X890000Y976500D03*
X974015Y261812D03*
X986614D03*
X974015Y267717D03*
Y255906D03*
X986614Y267717D03*
Y255906D03*
X969926Y847638D03*
X989100Y899600D03*
X1014500Y1153500D03*
X1012000Y1150000D03*
X1017500D03*
X1020000Y1153500D03*
X1119877Y423540D03*
Y428340D03*
Y418740D03*
X1124677Y428340D03*
Y423540D03*
Y418740D03*
X1105477Y428240D03*
Y423440D03*
X1100677D03*
Y428240D03*
X1105477Y418640D03*
X1100677D03*
X1128500Y1225700D03*
X1133300D03*
X1109400Y1221100D03*
X1114200D03*
Y1225900D03*
X1109400D03*
X1133300Y1220900D03*
X1128500D03*
X1133300Y1216100D03*
X1128500D03*
X1109400Y1216300D03*
X1114200D03*
X1066481Y1327759D03*
X1061081D03*
X1066481Y1333159D03*
X1061081D03*
X1066481Y1338559D03*
X1061081D03*
X1066481Y1343959D03*
X1061081D03*
X1066481Y1376359D03*
Y1349359D03*
Y1354759D03*
Y1360159D03*
Y1365559D03*
Y1370959D03*
X1061081Y1376359D03*
Y1370959D03*
Y1365559D03*
Y1360159D03*
Y1354759D03*
Y1349359D03*
X1870607Y75897D03*
X1823300Y88600D03*
X1863950Y45400D03*
G54D32*
X581800Y1321200D03*
Y1329100D03*
X589700D03*
Y1321200D03*
X594800Y1313500D03*
X597600Y1321200D03*
Y1329100D03*
X610600Y1313500D03*
Y1305600D03*
Y1297600D03*
X602700Y1313500D03*
Y1305600D03*
Y1297600D03*
X629200Y1329100D03*
X605500Y1321200D03*
X613400D03*
X605500Y1329100D03*
X613400D03*
X621300D03*
X581800Y1337000D03*
X589700D03*
X597600D03*
X629200D03*
X613400D03*
X621300D03*
X605500D03*
X1026100Y1145996D03*
G36*
G01X149667Y265962D02*
G02X112734I-18466J-14781D01*
G03X119307Y278426I-29176J23351D01*
G02X143094I11894J-3623D01*
G03X149667Y265962I35749J10887D01*
G37*
G36*
G01Y718718D02*
G02X112734I-18466J-14781D01*
G03X119307Y731182I-29176J23351D01*
G02X143094I11894J-3623D01*
G03X149667Y718718I35749J10887D01*
G37*
G36*
G01Y1171473D02*
G02X112734I-18466J-14781D01*
G03X119307Y1183937I-29176J23351D01*
G02X143094I11894J-3623D01*
G03X149667Y1171473I35749J10887D01*
G37*
G36*
G01X397699Y265962D02*
G02X360766I-18467J-14781D01*
G03X367339Y278426I-29176J23351D01*
G02X391126I11894J-3623D01*
G03X397699Y265962I35749J10887D01*
G37*
G36*
G01Y718718D02*
G02X360766I-18467J-14781D01*
G03X367339Y731182I-29176J23351D01*
G02X391126I11894J-3623D01*
G03X397699Y718718I35749J10887D01*
G37*
G36*
G01Y1171473D02*
G02X360766I-18467J-14781D01*
G03X367339Y1183937I-29176J23351D01*
G02X391126I11894J-3623D01*
G03X397699Y1171473I35749J10887D01*
G37*
G36*
G01X645730Y265962D02*
G02X608797I-18466J-14781D01*
G03X615370Y278426I-29176J23351D01*
G02X639157I11893J-3623D01*
G03X645730Y265962I35749J10887D01*
G37*
G36*
G01Y718718D02*
G02X608797I-18466J-14781D01*
G03X615370Y731182I-29176J23351D01*
G02X639157I11893J-3623D01*
G03X645730Y718718I35749J10887D01*
G37*
G36*
G01Y1171473D02*
G02X608797I-18466J-14781D01*
G03X615370Y1183937I-29176J23351D01*
G02X639157I11893J-3623D01*
G03X645730Y1171473I35749J10887D01*
G37*
G36*
G01X765711Y384859D02*
G02X728778I-18466J-14781D01*
G03X735351Y397323I-29176J23351D01*
G02X759138I11893J-3623D01*
G03X765711Y384859I35749J10887D01*
G37*
G36*
G01Y817930D02*
G02X728778I-18466J-14781D01*
G03X735351Y830394I-29176J23351D01*
G02X759138I11893J-3623D01*
G03X765711Y817930I35749J10887D01*
G37*
G36*
G01X979884Y706906D02*
G02X942951I-18467J-14781D01*
G03X949524Y719370I-29176J23351D01*
G02X973311I11894J-3623D01*
G03X979884Y706906I35749J10887D01*
G37*
G36*
G01Y975410D02*
G02X942951I-18467J-14781D01*
G03X949524Y987874I-29176J23351D01*
G02X973311I11894J-3623D01*
G03X979884Y975410I35749J10887D01*
G37*
G36*
G01X1200356Y384859D02*
G02X1163423I-18467J-14781D01*
G03X1169996Y397323I-29176J23351D01*
G02X1193783I11894J-3623D01*
G03X1200356Y384859I35749J10887D01*
G37*
G36*
G01Y975410D02*
G02X1163423I-18467J-14781D01*
G03X1169996Y987874I-29176J23351D01*
G02X1193783I11894J-3623D01*
G03X1200356Y975410I35749J10887D01*
G37*
G36*
G01X1320337Y265961D02*
G02X1283404I-18467J-14781D01*
G03X1289977Y278425I-29176J23351D01*
G02X1313764I11894J-3623D01*
G03X1320337Y265961I35749J10887D01*
G37*
G36*
G01Y718718D02*
G02X1283404I-18467J-14781D01*
G03X1289977Y731182I-29176J23351D01*
G02X1313764I11894J-3623D01*
G03X1320337Y718718I35749J10887D01*
G37*
G36*
G01Y1171473D02*
G02X1283404I-18467J-14781D01*
G03X1289977Y1183937I-29176J23351D01*
G02X1313764I11894J-3623D01*
G03X1320337Y1171473I35749J10887D01*
G37*
G36*
G01X1568368Y265962D02*
G02X1531435I-18467J-14781D01*
G03X1538008Y278426I-29176J23351D01*
G02X1561795I11894J-3623D01*
G03X1568368Y265962I35749J10887D01*
G37*
G36*
G01Y718718D02*
G02X1531435I-18467J-14781D01*
G03X1538008Y731182I-29176J23351D01*
G02X1561795I11894J-3623D01*
G03X1568368Y718718I35749J10887D01*
G37*
G36*
G01Y1171473D02*
G02X1531435I-18467J-14781D01*
G03X1538008Y1183937I-29176J23351D01*
G02X1561795I11894J-3623D01*
G03X1568368Y1171473I35749J10887D01*
G37*
G36*
G01X1816400Y265961D02*
G02X1779467I-18466J-14781D01*
G03X1786040Y278425I-29176J23351D01*
G02X1809827I11894J-3623D01*
G03X1816400Y265961I35749J10887D01*
G37*
G36*
G01Y718718D02*
G02X1779467I-18466J-14781D01*
G03X1786040Y731182I-29176J23351D01*
G02X1809827I11894J-3623D01*
G03X1816400Y718718I35749J10887D01*
G37*
G36*
G01Y1171473D02*
G02X1779467I-18466J-14781D01*
G03X1786040Y1183937I-29176J23351D01*
G02X1809827I11894J-3623D01*
G03X1816400Y1171473I35749J10887D01*
G37*
%LPC*%
G75*
G54D37*
G01X466941Y-145664D02*
Y-225664D01*
G01D02*
X1593241D01*
G01X462941Y-129664D02*
G02I-12000J0D01*
G01X457791D02*
G02I-6850J0D01*
G01X450941Y-145664D02*
Y-113664D01*
G01X466941Y-129664D02*
X434941D01*
G01X466941Y-145664D02*
X1593241D01*
G01X466941Y-181164D02*
X1593241D01*
G01X805741Y-145664D02*
Y-225664D01*
G01X943241Y-145664D02*
Y-225664D01*
G01X1058241Y-145664D02*
Y-225664D01*
G01X1225741Y-145664D02*
Y-225664D01*
G01X1395741Y-145664D02*
Y-225664D01*
G01X1593241Y-145664D02*
Y-225664D01*
G01X1621241Y-129664D02*
G02I-12000J0D01*
G01X1616091D02*
G02I-6850J0D01*
G01X1609241Y-145664D02*
Y-113664D01*
G01X1625241Y-129664D02*
X1593241D01*
G54D38*
G01X489037Y-206331D02*
X489911Y-205456D01*
X490566Y-203998D01*
X491003Y-201955D01*
X490566Y-200206D01*
X489693Y-199039D01*
X488164Y-198164D01*
X482269D01*
Y-215664D01*
X489474D01*
X491003Y-214498D01*
X491876Y-212747D01*
X492313Y-210706D01*
X491876Y-208664D01*
X490566Y-206914D01*
X489037Y-206331D01*
X482269D01*
G01X501734Y-215664D02*
Y-203998D01*
G01Y-206331D02*
X502826Y-205164D01*
X503918Y-204289D01*
X505446Y-203998D01*
X506537Y-204289D01*
X507848Y-205164D01*
G01X517706Y-220914D02*
X519016Y-221497D01*
X520763Y-220914D01*
X521854Y-219748D01*
X522728Y-218289D01*
X524037Y-213623D01*
X526876Y-203998D01*
G01X519889D02*
X524037Y-213623D01*
G01X543284Y-205456D02*
X541756Y-204289D01*
X540446Y-203998D01*
X538699Y-204581D01*
X537389Y-205747D01*
X536516Y-207789D01*
X536297Y-209831D01*
X536516Y-211873D01*
X537389Y-213623D01*
X538699Y-215081D01*
X540446Y-215664D01*
X541974Y-215081D01*
X543284Y-213914D01*
G01X554016Y-207789D02*
X561003D01*
X560348Y-205747D01*
X559256Y-204581D01*
X557728Y-203998D01*
X556199Y-204289D01*
X554889Y-205164D01*
X554016Y-207206D01*
X553579Y-208956D01*
Y-210706D01*
X554016Y-212456D01*
X555108Y-214206D01*
X556418Y-215372D01*
X557946Y-215664D01*
X559474Y-215081D01*
X561003Y-213331D01*
G01X597094Y-199623D02*
X595784Y-198747D01*
X594256Y-198164D01*
X592509D01*
X590544Y-199039D01*
X589016Y-200497D01*
X587924Y-202248D01*
X587051Y-205164D01*
X586832Y-207789D01*
X587269Y-210414D01*
X587924Y-212164D01*
X589234Y-213914D01*
X590763Y-215081D01*
X592291Y-215664D01*
X593819D01*
X595348Y-215081D01*
X596658Y-214206D01*
X597750Y-213040D01*
G01X613721Y-215664D02*
Y-203998D01*
G01Y-206039D02*
X612848Y-204873D01*
X611537Y-204289D01*
X610009Y-203998D01*
X608481Y-204581D01*
X607171Y-205747D01*
X606297Y-207497D01*
X605861Y-209831D01*
X606297Y-212164D01*
X607171Y-213914D01*
X608481Y-215081D01*
X610009Y-215664D01*
X611537Y-215372D01*
X612848Y-214498D01*
X613721Y-213331D01*
G01X623579Y-215664D02*
Y-203998D01*
G01Y-206914D02*
X624453Y-205456D01*
X625763Y-204289D01*
X627509Y-203998D01*
X629037Y-204289D01*
X630348Y-205456D01*
X631003Y-207497D01*
Y-215664D01*
G01X640206Y-220914D02*
X641516Y-221497D01*
X643263Y-220914D01*
X644354Y-219748D01*
X645228Y-218289D01*
X646537Y-213623D01*
X649376Y-203998D01*
G01X642389D02*
X646537Y-213623D01*
G01X662291Y-215664D02*
X660981Y-215372D01*
X659671Y-214206D01*
X658797Y-212164D01*
X658361Y-209831D01*
X658797Y-207497D01*
X659671Y-205456D01*
X660981Y-204289D01*
X662291Y-203998D01*
X663601Y-204289D01*
X664911Y-205456D01*
X665784Y-207497D01*
X666003Y-209831D01*
X665784Y-212164D01*
X664911Y-214206D01*
X663601Y-215372D01*
X662291Y-215664D01*
G01X676079D02*
Y-203998D01*
G01Y-206914D02*
X676953Y-205456D01*
X678263Y-204289D01*
X680009Y-203998D01*
X681537Y-204289D01*
X682848Y-205456D01*
X683503Y-207497D01*
Y-215664D01*
G01X710424D02*
Y-198164D01*
X715883D01*
X717629Y-199039D01*
X718721Y-200206D01*
X719158Y-202539D01*
X718721Y-204873D01*
X717411Y-206331D01*
X715883Y-207206D01*
X710424D01*
G01X715883D02*
X719158Y-215664D01*
G01X732291Y-216247D02*
X731854Y-215956D01*
Y-215372D01*
X732291Y-215081D01*
X732728Y-215372D01*
Y-215956D01*
X732291Y-216247D01*
G01X744988Y-215664D02*
Y-198164D01*
X749354D01*
X751101Y-199039D01*
X752411Y-200206D01*
X753503Y-201955D01*
X754376Y-203998D01*
X754594Y-206914D01*
X754376Y-209831D01*
X753503Y-211873D01*
X752411Y-213623D01*
X751101Y-214789D01*
X749354Y-215664D01*
X744988D01*
G01X762924D02*
Y-198164D01*
X768164D01*
X769911Y-199039D01*
X771221Y-201081D01*
X771658Y-203414D01*
X771221Y-205747D01*
X770129Y-207497D01*
X768164Y-208373D01*
X762924D01*
G01X786537Y-206331D02*
X787411Y-205456D01*
X788066Y-203998D01*
X788503Y-201955D01*
X788066Y-200206D01*
X787193Y-199039D01*
X785664Y-198164D01*
X779769D01*
Y-215664D01*
X786974D01*
X788503Y-214498D01*
X789376Y-212747D01*
X789813Y-210706D01*
X789376Y-208664D01*
X788066Y-206914D01*
X786537Y-206331D01*
X779769D01*
G01X595364Y-170664D02*
Y-153164D01*
X601041Y-167747D01*
X606718Y-153164D01*
Y-170664D01*
G01X618541D02*
X617231Y-170372D01*
X615921Y-169206D01*
X615047Y-167164D01*
X614611Y-164831D01*
X615047Y-162497D01*
X615921Y-160456D01*
X617231Y-159289D01*
X618541Y-158998D01*
X619851Y-159289D01*
X621161Y-160456D01*
X622034Y-162497D01*
X622253Y-164831D01*
X622034Y-167164D01*
X621161Y-169206D01*
X619851Y-170372D01*
X618541Y-170664D01*
G01X639971Y-153164D02*
Y-170664D01*
G01Y-168040D02*
X639098Y-169498D01*
X637787Y-170372D01*
X636259Y-170664D01*
X634513Y-170081D01*
X633203Y-168623D01*
X632329Y-166873D01*
X632111Y-164831D01*
X632329Y-162789D01*
X633203Y-161039D01*
X634513Y-159581D01*
X636259Y-158998D01*
X637787Y-159289D01*
X638879Y-159873D01*
X639971Y-161039D01*
G01X650266Y-162789D02*
X657253D01*
X656598Y-160747D01*
X655506Y-159581D01*
X653978Y-158998D01*
X652449Y-159289D01*
X651139Y-160164D01*
X650266Y-162206D01*
X649829Y-163956D01*
Y-165706D01*
X650266Y-167456D01*
X651358Y-169206D01*
X652668Y-170372D01*
X654196Y-170664D01*
X655724Y-170081D01*
X657253Y-168331D01*
G01X671041Y-170664D02*
Y-153164D01*
G01X839441Y-215664D02*
Y-198164D01*
X836821Y-201664D01*
G01Y-215664D02*
X842061D01*
G01X852793Y-208373D02*
X854321Y-206331D01*
X855631Y-205164D01*
X857378Y-204581D01*
X858906Y-205164D01*
X859998Y-206331D01*
X860871Y-208081D01*
X861089Y-210122D01*
X860871Y-211873D01*
X859998Y-213623D01*
X858687Y-215081D01*
X857159Y-215664D01*
X855413Y-215081D01*
X853884Y-213331D01*
X853011Y-210706D01*
X852793Y-207789D01*
X853229Y-203998D01*
X853884Y-201955D01*
X854976Y-199914D01*
X856504Y-198456D01*
X858033Y-198164D01*
X859561Y-198747D01*
X860653Y-200206D01*
G01X869638Y-212164D02*
X870947Y-214206D01*
X872694Y-215372D01*
X874659Y-215664D01*
X876406Y-215372D01*
X878153Y-213914D01*
X879244Y-212164D01*
X879463Y-210414D01*
X879026Y-208373D01*
X877498Y-206914D01*
X875969Y-206331D01*
X874004D01*
G01X875969D02*
X877279Y-205456D01*
X878371Y-203998D01*
X878808Y-202248D01*
X878371Y-200497D01*
X877279Y-199039D01*
X875314Y-198164D01*
X873349Y-198456D01*
X871384Y-199623D01*
G01X891941Y-215664D02*
Y-198164D01*
X889321Y-201664D01*
G01Y-215664D02*
X894561D01*
G01X909004D02*
X909441Y-211873D01*
X910096Y-208664D01*
X910969Y-205747D01*
X912061Y-202539D01*
X913808Y-198164D01*
X905074D01*
G01X826324Y-170664D02*
Y-153164D01*
X831564D01*
X833311Y-154039D01*
X834621Y-156081D01*
X835058Y-158414D01*
X834621Y-160747D01*
X833529Y-162497D01*
X831564Y-163373D01*
X826324D01*
G01X852994Y-154623D02*
X851684Y-153747D01*
X850156Y-153164D01*
X848409D01*
X846444Y-154039D01*
X844916Y-155497D01*
X843824Y-157248D01*
X842951Y-160164D01*
X842732Y-162789D01*
X843169Y-165414D01*
X843824Y-167164D01*
X845134Y-168914D01*
X846663Y-170081D01*
X848191Y-170664D01*
X849719D01*
X851248Y-170081D01*
X852558Y-169206D01*
X853650Y-168040D01*
G01X867437Y-161331D02*
X868311Y-160456D01*
X868966Y-158998D01*
X869403Y-156955D01*
X868966Y-155206D01*
X868093Y-154039D01*
X866564Y-153164D01*
X860669D01*
Y-170664D01*
X867874D01*
X869403Y-169498D01*
X870276Y-167747D01*
X870713Y-165706D01*
X870276Y-163664D01*
X868966Y-161914D01*
X867437Y-161331D01*
X860669D01*
G01X876641Y-176497D02*
X889741D01*
G01X895669Y-170664D02*
Y-153164D01*
X905713Y-170664D01*
Y-153164D01*
G01X918191Y-170664D02*
X916444Y-170372D01*
X914916Y-169206D01*
X913606Y-167456D01*
X912732Y-165414D01*
X912296Y-163081D01*
Y-160747D01*
X912732Y-158414D01*
X913606Y-156372D01*
X914916Y-154623D01*
X916444Y-153456D01*
X918191Y-153164D01*
X919937Y-153456D01*
X921466Y-154623D01*
X922776Y-156372D01*
X923650Y-158414D01*
X924086Y-160747D01*
Y-163081D01*
X923650Y-165414D01*
X922776Y-167456D01*
X921466Y-169206D01*
X919937Y-170372D01*
X918191Y-170664D01*
G01X1000741Y-215664D02*
Y-198164D01*
X998121Y-201664D01*
G01Y-215664D02*
X1003361D01*
G01X969032Y-153164D02*
X974491Y-170664D01*
X979950Y-153164D01*
G01X996358Y-170664D02*
X987624D01*
Y-153164D01*
X996358D01*
G01X992864Y-161622D02*
X987624D01*
G01X1005124Y-170664D02*
Y-153164D01*
X1010583D01*
X1012329Y-154039D01*
X1013421Y-155206D01*
X1013858Y-157539D01*
X1013421Y-159873D01*
X1012111Y-161331D01*
X1010583Y-162206D01*
X1005124D01*
G01X1010583D02*
X1013858Y-170664D01*
G01X1026991Y-171247D02*
X1026554Y-170956D01*
Y-170372D01*
X1026991Y-170081D01*
X1027428Y-170372D01*
Y-170956D01*
X1026991Y-171247D01*
G01X1102574Y-198164D02*
Y-215664D01*
X1111308D01*
G01X1127061D02*
Y-198164D01*
X1118982Y-210706D01*
X1129900D01*
G01X1136482Y-198164D02*
X1141941Y-215664D01*
X1147400Y-198164D01*
G01X1164244Y-199623D02*
X1162934Y-198747D01*
X1161406Y-198164D01*
X1159659D01*
X1157694Y-199039D01*
X1156166Y-200497D01*
X1155074Y-202248D01*
X1154201Y-205164D01*
X1153982Y-207789D01*
X1154419Y-210414D01*
X1155074Y-212164D01*
X1156384Y-213914D01*
X1157913Y-215081D01*
X1159441Y-215664D01*
X1160969D01*
X1162498Y-215081D01*
X1163808Y-214206D01*
X1164900Y-213040D01*
G01X1181744Y-199623D02*
X1180434Y-198747D01*
X1178906Y-198164D01*
X1177159D01*
X1175194Y-199039D01*
X1173666Y-200497D01*
X1172574Y-202248D01*
X1171701Y-205164D01*
X1171482Y-207789D01*
X1171919Y-210414D01*
X1172574Y-212164D01*
X1173884Y-213914D01*
X1175413Y-215081D01*
X1176941Y-215664D01*
X1178469D01*
X1179998Y-215081D01*
X1181308Y-214206D01*
X1182400Y-213040D01*
G01X1102574Y-153164D02*
Y-170664D01*
X1111308D01*
G01X1128371D02*
Y-158998D01*
G01Y-161039D02*
X1127498Y-159873D01*
X1126187Y-159289D01*
X1124659Y-158998D01*
X1123131Y-159581D01*
X1121821Y-160747D01*
X1120947Y-162497D01*
X1120511Y-164831D01*
X1120947Y-167164D01*
X1121821Y-168914D01*
X1123131Y-170081D01*
X1124659Y-170664D01*
X1126187Y-170372D01*
X1127498Y-169498D01*
X1128371Y-168331D01*
G01X1137356Y-175914D02*
X1138666Y-176497D01*
X1140413Y-175914D01*
X1141504Y-174748D01*
X1142378Y-173289D01*
X1143687Y-168623D01*
X1146526Y-158998D01*
G01X1139539D02*
X1143687Y-168623D01*
G01X1156166Y-162789D02*
X1163153D01*
X1162498Y-160747D01*
X1161406Y-159581D01*
X1159878Y-158998D01*
X1158349Y-159289D01*
X1157039Y-160164D01*
X1156166Y-162206D01*
X1155729Y-163956D01*
Y-165706D01*
X1156166Y-167456D01*
X1157258Y-169206D01*
X1158568Y-170372D01*
X1160096Y-170664D01*
X1161624Y-170081D01*
X1163153Y-168331D01*
G01X1173884Y-170664D02*
Y-158998D01*
G01Y-161331D02*
X1174976Y-160164D01*
X1176068Y-159289D01*
X1177596Y-158998D01*
X1178687Y-159289D01*
X1179998Y-160164D01*
G01X1244688Y-170664D02*
Y-153164D01*
X1249054D01*
X1250801Y-154039D01*
X1252111Y-155206D01*
X1253203Y-156955D01*
X1254076Y-158998D01*
X1254294Y-161914D01*
X1254076Y-164831D01*
X1253203Y-166873D01*
X1252111Y-168623D01*
X1250801Y-169789D01*
X1249054Y-170664D01*
X1244688D01*
G01X1263716Y-162789D02*
X1270703D01*
X1270048Y-160747D01*
X1268956Y-159581D01*
X1267428Y-158998D01*
X1265899Y-159289D01*
X1264589Y-160164D01*
X1263716Y-162206D01*
X1263279Y-163956D01*
Y-165706D01*
X1263716Y-167456D01*
X1264808Y-169206D01*
X1266118Y-170372D01*
X1267646Y-170664D01*
X1269174Y-170081D01*
X1270703Y-168331D01*
G01X1281216Y-168623D02*
X1282308Y-169789D01*
X1283836Y-170664D01*
X1285146D01*
X1286456Y-170081D01*
X1287329Y-169206D01*
X1287766Y-168040D01*
X1287548Y-166289D01*
X1286674Y-165414D01*
X1282744Y-163664D01*
X1281871Y-161622D01*
X1282308Y-160164D01*
X1283181Y-159289D01*
X1284491Y-158998D01*
X1285801Y-159289D01*
X1287111Y-160164D01*
G01X1301991Y-158998D02*
Y-170664D01*
G01Y-154331D02*
X1301554Y-154039D01*
Y-153456D01*
X1301991Y-153164D01*
X1302428Y-153456D01*
Y-154039D01*
X1301991Y-154331D01*
G01X1316434Y-175039D02*
X1317963Y-176206D01*
X1319709Y-176497D01*
X1321237Y-176206D01*
X1322548Y-174748D01*
X1323421Y-172706D01*
Y-158998D01*
G01Y-161331D02*
X1322548Y-160164D01*
X1321237Y-159289D01*
X1319709Y-158998D01*
X1317963Y-159581D01*
X1316871Y-160747D01*
X1315997Y-162789D01*
X1315561Y-164831D01*
X1315779Y-166581D01*
X1316653Y-168623D01*
X1317963Y-170081D01*
X1319709Y-170664D01*
X1321019Y-170372D01*
X1322548Y-169206D01*
X1323421Y-168040D01*
G01X1333279Y-170664D02*
Y-158998D01*
G01Y-161914D02*
X1334153Y-160456D01*
X1335463Y-159289D01*
X1337209Y-158998D01*
X1338737Y-159289D01*
X1340048Y-160456D01*
X1340703Y-162497D01*
Y-170664D01*
G01X1351216Y-162789D02*
X1358203D01*
X1357548Y-160747D01*
X1356456Y-159581D01*
X1354928Y-158998D01*
X1353399Y-159289D01*
X1352089Y-160164D01*
X1351216Y-162206D01*
X1350779Y-163956D01*
Y-165706D01*
X1351216Y-167456D01*
X1352308Y-169206D01*
X1353618Y-170372D01*
X1355146Y-170664D01*
X1356674Y-170081D01*
X1358203Y-168331D01*
G01X1368934Y-170664D02*
Y-158998D01*
G01Y-161331D02*
X1370026Y-160164D01*
X1371118Y-159289D01*
X1372646Y-158998D01*
X1373737Y-159289D01*
X1375048Y-160164D01*
G01X1266991Y-215664D02*
X1265244Y-215372D01*
X1263716Y-214206D01*
X1262406Y-212456D01*
X1261532Y-210414D01*
X1261096Y-208081D01*
Y-205747D01*
X1261532Y-203414D01*
X1262406Y-201372D01*
X1263716Y-199623D01*
X1265244Y-198456D01*
X1266991Y-198164D01*
X1268737Y-198456D01*
X1270266Y-199623D01*
X1271576Y-201372D01*
X1272450Y-203414D01*
X1272886Y-205747D01*
Y-208081D01*
X1272450Y-210414D01*
X1271576Y-212456D01*
X1270266Y-214206D01*
X1268737Y-215372D01*
X1266991Y-215664D01*
G01X1268737Y-210997D02*
X1271358Y-215664D01*
G01X1279688Y-198164D02*
Y-210706D01*
X1280561Y-213331D01*
X1282308Y-215081D01*
X1284491Y-215664D01*
X1286674Y-215081D01*
X1288421Y-213331D01*
X1289294Y-210706D01*
Y-198164D01*
G01X1299371D02*
X1304611D01*
G01X1301991D02*
Y-215664D01*
G01X1299371D02*
X1304611D01*
G01X1314469D02*
Y-198164D01*
X1324513Y-215664D01*
Y-198164D01*
G01X1341794Y-199623D02*
X1340484Y-198747D01*
X1338956Y-198164D01*
X1337209D01*
X1335244Y-199039D01*
X1333716Y-200497D01*
X1332624Y-202248D01*
X1331751Y-205164D01*
X1331532Y-207789D01*
X1331969Y-210414D01*
X1332624Y-212164D01*
X1333934Y-213914D01*
X1335463Y-215081D01*
X1336991Y-215664D01*
X1338519D01*
X1340048Y-215081D01*
X1341358Y-214206D01*
X1342450Y-213040D01*
G01X1354491Y-215664D02*
Y-207789D01*
X1350124Y-198164D01*
G01X1358858D02*
X1354491Y-207789D01*
G01X1415691Y-198164D02*
X1413944Y-198747D01*
X1412634Y-200206D01*
X1411761Y-201955D01*
X1411106Y-204289D01*
X1410888Y-206914D01*
X1411106Y-209539D01*
X1411761Y-211873D01*
X1412634Y-213623D01*
X1413944Y-215081D01*
X1415691Y-215664D01*
X1417437Y-215081D01*
X1418748Y-213623D01*
X1419621Y-211873D01*
X1420276Y-209539D01*
X1420494Y-206914D01*
X1420276Y-204289D01*
X1419621Y-201955D01*
X1418748Y-200206D01*
X1417437Y-198747D01*
X1415691Y-198164D01*
G01X1429043Y-208373D02*
X1430571Y-206331D01*
X1431881Y-205164D01*
X1433628Y-204581D01*
X1435156Y-205164D01*
X1436248Y-206331D01*
X1437121Y-208081D01*
X1437339Y-210122D01*
X1437121Y-211873D01*
X1436248Y-213623D01*
X1434937Y-215081D01*
X1433409Y-215664D01*
X1431663Y-215081D01*
X1430134Y-213331D01*
X1429261Y-210706D01*
X1429043Y-207789D01*
X1429479Y-203998D01*
X1430134Y-201955D01*
X1431226Y-199914D01*
X1432754Y-198456D01*
X1434283Y-198164D01*
X1435811Y-198747D01*
X1436903Y-200206D01*
G01X1446761Y-216247D02*
X1454621Y-198164D01*
G01X1468191D02*
X1466444Y-198747D01*
X1465134Y-200206D01*
X1464261Y-201955D01*
X1463606Y-204289D01*
X1463388Y-206914D01*
X1463606Y-209539D01*
X1464261Y-211873D01*
X1465134Y-213623D01*
X1466444Y-215081D01*
X1468191Y-215664D01*
X1469937Y-215081D01*
X1471248Y-213623D01*
X1472121Y-211873D01*
X1472776Y-209539D01*
X1472994Y-206914D01*
X1472776Y-204289D01*
X1472121Y-201955D01*
X1471248Y-200206D01*
X1469937Y-198747D01*
X1468191Y-198164D01*
G01X1481979Y-213623D02*
X1483508Y-215081D01*
X1485254Y-215664D01*
X1487001Y-215081D01*
X1488529Y-213331D01*
X1489621Y-210706D01*
X1490058Y-208081D01*
Y-204873D01*
X1489621Y-202248D01*
X1488529Y-199914D01*
X1487219Y-198747D01*
X1485691Y-198164D01*
X1483944Y-198747D01*
X1482634Y-199914D01*
X1481761Y-201664D01*
X1481324Y-203998D01*
X1481761Y-206039D01*
X1482853Y-208081D01*
X1484163Y-209248D01*
X1485691Y-209539D01*
X1487437Y-208956D01*
X1488748Y-207497D01*
X1490058Y-204873D01*
G01X1499261Y-216247D02*
X1507121Y-198164D01*
G01X1516543Y-201081D02*
X1517853Y-199331D01*
X1519381Y-198456D01*
X1521128Y-198164D01*
X1523311Y-198747D01*
X1524839Y-200206D01*
X1525276Y-201955D01*
X1525058Y-203706D01*
X1524184Y-205164D01*
X1519818Y-208081D01*
X1517853Y-210122D01*
X1516543Y-213040D01*
X1516106Y-215664D01*
X1525276D01*
G01X1538191Y-198164D02*
X1536444Y-198747D01*
X1535134Y-200206D01*
X1534261Y-201955D01*
X1533606Y-204289D01*
X1533388Y-206914D01*
X1533606Y-209539D01*
X1534261Y-211873D01*
X1535134Y-213623D01*
X1536444Y-215081D01*
X1538191Y-215664D01*
X1539937Y-215081D01*
X1541248Y-213623D01*
X1542121Y-211873D01*
X1542776Y-209539D01*
X1542994Y-206914D01*
X1542776Y-204289D01*
X1542121Y-201955D01*
X1541248Y-200206D01*
X1539937Y-198747D01*
X1538191Y-198164D01*
G01X1555691Y-215664D02*
Y-198164D01*
X1553071Y-201664D01*
G01Y-215664D02*
X1558311D01*
G01X1572754D02*
X1573191Y-211873D01*
X1573846Y-208664D01*
X1574719Y-205747D01*
X1575811Y-202539D01*
X1577558Y-198164D01*
X1568824D01*
G01X1463388Y-170664D02*
Y-153164D01*
X1467754D01*
X1469501Y-154039D01*
X1470811Y-155206D01*
X1471903Y-156955D01*
X1472776Y-158998D01*
X1472994Y-161914D01*
X1472776Y-164831D01*
X1471903Y-166873D01*
X1470811Y-168623D01*
X1469501Y-169789D01*
X1467754Y-170664D01*
X1463388D01*
G01X1489621D02*
Y-158998D01*
G01Y-161039D02*
X1488748Y-159873D01*
X1487437Y-159289D01*
X1485909Y-158998D01*
X1484381Y-159581D01*
X1483071Y-160747D01*
X1482197Y-162497D01*
X1481761Y-164831D01*
X1482197Y-167164D01*
X1483071Y-168914D01*
X1484381Y-170081D01*
X1485909Y-170664D01*
X1487437Y-170372D01*
X1488748Y-169498D01*
X1489621Y-168331D01*
G01X1503191Y-153164D02*
Y-170664D01*
G01X1500134Y-158998D02*
X1506248D01*
G01X1517416Y-162789D02*
X1524403D01*
X1523748Y-160747D01*
X1522656Y-159581D01*
X1521128Y-158998D01*
X1519599Y-159289D01*
X1518289Y-160164D01*
X1517416Y-162206D01*
X1516979Y-163956D01*
Y-165706D01*
X1517416Y-167456D01*
X1518508Y-169206D01*
X1519818Y-170372D01*
X1521346Y-170664D01*
X1522874Y-170081D01*
X1524403Y-168331D01*
M02*
